FILE_TYPE = MACRO_DRAWING;
SET COLOR_WIRE YELLOW;
SET COLOR_PROP ORANGE;
SET COLOR_DOT WHITE;
SET COLOR_ARC YELLOW;
SET COLOR_BODY GREEN;
SET COLOR_NOTE PURPLE;
SET PROP_DISPLAY VALUE;
SET PAGE_NUMBER P187;
FORCEADD UNIVERSAL_GND..1
(-7775 4350);
FORCEPROP 3 LASTPIN (-7775 4400) SIG_NAME GND\g
J 0
(-7765 4410);
DISPLAY 0.659574 (-7765 4410);
PAINT MONO (-7765 4410);
DISPLAY INVISIBLE (-7765 4410);
FORCEPROP 2 LAST CDS_LIB pure_quanta_power
J 0
(-7775 4350);
DISPLAY INVISIBLE (-7775 4350);
FORCEPROP 1 LAST PATH I1
J 0
(-7700 4350);
DISPLAY 0.872340 (-7700 4350);
PAINT AQUA (-7700 4350);
DISPLAY INVISIBLE (-7700 4350);
FORCEPROP 1 LAST HDL_POWER GND
J 1
(-7750 4275);
DISPLAY 0.872340 (-7750 4275);
PAINT GREEN (-7750 4275);
DISPLAY INVISIBLE (-7750 4275);
FORCEADD OFFPAGE..2
R 2
(-7000 1100);
FORCEPROP 2 LAST $XR3 186 
J 0
(-7495 1064);
DISPLAY 0.638298 (-7495 1064);
PAINT MONO (-7495 1064);
FORCEPROP 2 LAST $XR2 189 
J 0
(-7375 1064);
DISPLAY 0.638298 (-7375 1064);
PAINT MONO (-7375 1064);
FORCEPROP 2 LAST $XR1 188 
J 0
(-7255 1064);
DISPLAY 0.638298 (-7255 1064);
PAINT MONO (-7255 1064);
FORCEPROP 2 LAST $XR0 187 
J 0
(-7255 1100);
DISPLAY 0.638298 (-7255 1100);
PAINT MONO (-7255 1100);
FORCEPROP 2 LAST PATH I101
J 0
(-6950 1175);
DISPLAY 1.021277 (-6950 1175);
DISPLAY INVISIBLE (-6950 1175);
FORCEPROP 1 LAST COMMENT_BODY TRUE
J 2
(-6955 1005);
DISPLAY 0.872340 (-6955 1005);
PAINT GREEN (-6955 1005);
DISPLAY INVISIBLE (-6955 1005);
FORCEPROP 1 LAST OFFPAGE TRUE
J 2
(-7325 975);
DISPLAY 0.872340 (-7325 975);
PAINT GREEN (-7325 975);
DISPLAY INVISIBLE (-7325 975);
FORCEPROP 2 LAST CDS_LIB standard
J 0
(-7000 1100);
DISPLAY INVISIBLE (-7000 1100);
FORCEADD UNIVERSAL_GND..1
(-7375 1125);
FORCEPROP 3 LASTPIN (-7375 1175) SIG_NAME GND\g
J 0
(-7365 1185);
DISPLAY 0.659574 (-7365 1185);
PAINT MONO (-7365 1185);
DISPLAY INVISIBLE (-7365 1185);
FORCEPROP 2 LAST CDS_LIB pure_quanta_power
J 0
(-7375 1125);
DISPLAY INVISIBLE (-7375 1125);
FORCEPROP 1 LAST PATH I102
J 0
(-7300 1125);
DISPLAY 0.872340 (-7300 1125);
PAINT AQUA (-7300 1125);
DISPLAY INVISIBLE (-7300 1125);
FORCEPROP 1 LAST HDL_POWER GND
J 1
(-7350 1050);
DISPLAY 0.872340 (-7350 1050);
PAINT GREEN (-7350 1050);
DISPLAY INVISIBLE (-7350 1050);
FORCEADD OFFPAGE..1
(-6975 1000);
FORCEPROP 2 LAST $XR0 186 
J 0
(-7227 1000);
DISPLAY 0.638298 (-7227 1000);
PAINT MONO (-7227 1000);
FORCEPROP 2 LAST PATH I103
J 0
(-6925 1075);
DISPLAY 1.021277 (-6925 1075);
DISPLAY INVISIBLE (-6925 1075);
FORCEPROP 1 LAST COMMENT_BODY TRUE
J 0
(-6850 900);
DISPLAY 0.872340 (-6850 900);
PAINT GREEN (-6850 900);
DISPLAY INVISIBLE (-6850 900);
FORCEPROP 1 LAST OFFPAGE TRUE
J 0
(-6650 875);
DISPLAY 0.872340 (-6650 875);
PAINT GREEN (-6650 875);
DISPLAY INVISIBLE (-6650 875);
FORCEPROP 2 LAST CDS_LIB standard
J 2
(-6975 1000);
DISPLAY INVISIBLE (-6975 1000);
FORCEADD OFFPAGE..1
(-7925 1500);
FORCEPROP 2 LAST $XR5 192 
J 0
(-8807 1500);
DISPLAY 0.638298 (-8807 1500);
PAINT MONO (-8807 1500);
FORCEPROP 2 LAST $XR4 191 
J 0
(-8687 1500);
DISPLAY 0.638298 (-8687 1500);
PAINT MONO (-8687 1500);
FORCEPROP 2 LAST $XR3 189 
J 0
(-8567 1500);
DISPLAY 0.638298 (-8567 1500);
PAINT MONO (-8567 1500);
FORCEPROP 2 LAST $XR2 188 
J 0
(-8447 1500);
DISPLAY 0.638298 (-8447 1500);
PAINT MONO (-8447 1500);
FORCEPROP 2 LAST $XR1 187 
J 0
(-8327 1500);
DISPLAY 0.638298 (-8327 1500);
PAINT MONO (-8327 1500);
FORCEPROP 2 LAST $XR0 186 
J 0
(-8207 1500);
DISPLAY 0.638298 (-8207 1500);
PAINT MONO (-8207 1500);
FORCEPROP 2 LAST PATH I104
J 0
(-7875 1575);
DISPLAY 1.021277 (-7875 1575);
DISPLAY INVISIBLE (-7875 1575);
FORCEPROP 1 LAST COMMENT_BODY TRUE
J 0
(-7800 1400);
DISPLAY 0.872340 (-7800 1400);
PAINT GREEN (-7800 1400);
DISPLAY INVISIBLE (-7800 1400);
FORCEPROP 1 LAST OFFPAGE TRUE
J 0
(-7600 1375);
DISPLAY 0.872340 (-7600 1375);
PAINT GREEN (-7600 1375);
DISPLAY INVISIBLE (-7600 1375);
FORCEPROP 2 LAST CDS_LIB standard
J 0
(-7925 1500);
DISPLAY INVISIBLE (-7925 1500);
FORCEADD Q_CAP..1
(-7700 1325);
FORCEPROP 1 LAST LOCATION PC285_4
J 0
(-7650 1425);
DISPLAY 0.489362 (-7650 1425);
PAINT SKYBLUE (-7650 1425);
FORCEPROP 0 LAST $SEC 1
J 0
(-7650 1450);
DISPLAY 0.680851 (-7650 1450);
PAINT MONO (-7650 1450);
DISPLAY INVISIBLE (-7650 1450);
FORCEPROP 0 LAST CDS_SEC 1
J 0
(-7650 1450);
DISPLAY 1.021277 (-7650 1450);
DISPLAY INVISIBLE (-7650 1450);
FORCEPROP 1 LASTPIN (-7700 1425) $PN 1
J 0
(-7690 1405);
DISPLAY 0.489362 (-7690 1405);
PAINT MONO (-7690 1405);
FORCEPROP 1 LASTPIN (-7700 1225) $PN 2
J 0
(-7690 1205);
DISPLAY 0.489362 (-7690 1205);
PAINT MONO (-7690 1205);
FORCEPROP 1 LAST MATERIAL X7R
J 0
(-7650 1225);
DISPLAY 0.489362 (-7650 1225);
PAINT SKYBLUE (-7650 1225);
FORCEPROP 1 LAST TOLERANCE 10%
J 0
(-7650 1275);
DISPLAY 0.489362 (-7650 1275);
PAINT SKYBLUE (-7650 1275);
FORCEPROP 1 LAST VALUE 0.1UF
J 0
(-7650 1375);
DISPLAY 0.489362 (-7650 1375);
PAINT SKYBLUE (-7650 1375);
FORCEPROP 1 LAST PART_NUMBER CH4104K1B00
J 0
(-7650 1175);
DISPLAY 0.489362 (-7650 1175);
PAINT SKYBLUE (-7650 1175);
FORCEPROP 1 LAST VOLTAGE 25V
J 0
(-7650 1325);
DISPLAY 0.489362 (-7650 1325);
PAINT SKYBLUE (-7650 1325);
FORCEPROP 1 LAST PACK_TYPE 0402
J 0
(-7650 1125);
DISPLAY 0.489362 (-7650 1125);
PAINT SKYBLUE (-7650 1125);
FORCEPROP 2 LAST CDS_LIB pure_quanta
J 0
(-7700 1325);
DISPLAY INVISIBLE (-7700 1325);
FORCEPROP 1 LAST PATH I105
J 0
(-7650 1475);
DISPLAY 0.978723 (-7650 1475);
PAINT WHITE (-7650 1475);
DISPLAY INVISIBLE (-7650 1475);
FORCEADD UNIVERSAL_GND..1
(-7700 1050);
FORCEPROP 3 LASTPIN (-7700 1100) SIG_NAME GND\g
J 0
(-7690 1110);
DISPLAY 0.659574 (-7690 1110);
PAINT MONO (-7690 1110);
DISPLAY INVISIBLE (-7690 1110);
FORCEPROP 2 LAST CDS_LIB pure_quanta_power
J 0
(-7700 1050);
DISPLAY INVISIBLE (-7700 1050);
FORCEPROP 1 LAST PATH I106
J 0
(-7625 1050);
DISPLAY 0.872340 (-7625 1050);
PAINT AQUA (-7625 1050);
DISPLAY INVISIBLE (-7625 1050);
FORCEPROP 1 LAST HDL_POWER GND
J 1
(-7675 975);
DISPLAY 0.872340 (-7675 975);
PAINT GREEN (-7675 975);
DISPLAY INVISIBLE (-7675 975);
FORCEADD Q_CAP..1
(-5325 5800);
FORCEPROP 1 LAST LOCATION PC290_3
J 0
(-5275 5900);
DISPLAY 0.489362 (-5275 5900);
PAINT SKYBLUE (-5275 5900);
FORCEPROP 0 LAST $SEC 1
J 0
(-5275 5950);
DISPLAY 0.680851 (-5275 5950);
PAINT MONO (-5275 5950);
DISPLAY INVISIBLE (-5275 5950);
FORCEPROP 0 LAST CDS_SEC 1
J 0
(-5275 5950);
DISPLAY 1.021277 (-5275 5950);
DISPLAY INVISIBLE (-5275 5950);
FORCEPROP 1 LASTPIN (-5325 5900) $PN 1
J 0
(-5315 5880);
DISPLAY 0.489362 (-5315 5880);
PAINT MONO (-5315 5880);
FORCEPROP 1 LASTPIN (-5325 5700) $PN 2
J 0
(-5315 5680);
DISPLAY 0.489362 (-5315 5680);
PAINT MONO (-5315 5680);
FORCEPROP 1 LAST MATERIAL X7R
J 0
(-5275 5700);
DISPLAY 0.489362 (-5275 5700);
PAINT SKYBLUE (-5275 5700);
FORCEPROP 1 LAST TOLERANCE 10%
J 0
(-5275 5750);
DISPLAY 0.489362 (-5275 5750);
PAINT SKYBLUE (-5275 5750);
FORCEPROP 1 LAST VALUE 0.1UF
J 0
(-5275 5850);
DISPLAY 0.489362 (-5275 5850);
PAINT SKYBLUE (-5275 5850);
FORCEPROP 1 LAST PART_NUMBER CH4104K1B00
J 0
(-5275 5650);
DISPLAY 0.489362 (-5275 5650);
PAINT SKYBLUE (-5275 5650);
FORCEPROP 1 LAST VOLTAGE 25V
J 0
(-5275 5800);
DISPLAY 0.489362 (-5275 5800);
PAINT SKYBLUE (-5275 5800);
FORCEPROP 1 LAST PACK_TYPE 0402
J 0
(-5275 5600);
DISPLAY 0.489362 (-5275 5600);
PAINT SKYBLUE (-5275 5600);
FORCEPROP 2 LAST CDS_LIB pure_quanta
J 0
(-5325 5800);
DISPLAY INVISIBLE (-5325 5800);
FORCEPROP 1 LAST PATH I107
J 0
(-5275 5950);
DISPLAY 0.978723 (-5275 5950);
PAINT WHITE (-5275 5950);
DISPLAY INVISIBLE (-5275 5950);
FORCEADD Q_CAP..1
(-5200 2500);
FORCEPROP 1 LAST LOCATION PC291_4
J 0
(-5150 2600);
DISPLAY 0.489362 (-5150 2600);
PAINT SKYBLUE (-5150 2600);
FORCEPROP 0 LAST $SEC 1
J 0
(-5150 2650);
DISPLAY 0.680851 (-5150 2650);
PAINT MONO (-5150 2650);
DISPLAY INVISIBLE (-5150 2650);
FORCEPROP 0 LAST CDS_SEC 1
J 0
(-5150 2650);
DISPLAY 1.021277 (-5150 2650);
DISPLAY INVISIBLE (-5150 2650);
FORCEPROP 1 LASTPIN (-5200 2600) $PN 1
J 0
(-5190 2580);
DISPLAY 0.489362 (-5190 2580);
PAINT MONO (-5190 2580);
FORCEPROP 1 LASTPIN (-5200 2400) $PN 2
J 0
(-5190 2380);
DISPLAY 0.489362 (-5190 2380);
PAINT MONO (-5190 2380);
FORCEPROP 1 LAST MATERIAL X7R
J 0
(-5150 2400);
DISPLAY 0.489362 (-5150 2400);
PAINT SKYBLUE (-5150 2400);
FORCEPROP 1 LAST TOLERANCE 10%
J 0
(-5150 2450);
DISPLAY 0.489362 (-5150 2450);
PAINT SKYBLUE (-5150 2450);
FORCEPROP 1 LAST VALUE 0.1UF
J 0
(-5150 2550);
DISPLAY 0.489362 (-5150 2550);
PAINT SKYBLUE (-5150 2550);
FORCEPROP 1 LAST PART_NUMBER CH4104K1B00
J 0
(-5150 2350);
DISPLAY 0.489362 (-5150 2350);
PAINT SKYBLUE (-5150 2350);
FORCEPROP 1 LAST VOLTAGE 25V
J 0
(-5150 2500);
DISPLAY 0.489362 (-5150 2500);
PAINT SKYBLUE (-5150 2500);
FORCEPROP 1 LAST PACK_TYPE 0402
J 0
(-5150 2300);
DISPLAY 0.489362 (-5150 2300);
PAINT SKYBLUE (-5150 2300);
FORCEPROP 2 LAST CDS_LIB pure_quanta
J 0
(-5200 2500);
DISPLAY INVISIBLE (-5200 2500);
FORCEPROP 1 LAST PATH I108
J 0
(-5150 2650);
DISPLAY 0.978723 (-5150 2650);
PAINT WHITE (-5150 2650);
DISPLAY INVISIBLE (-5150 2650);
FORCEADD Q_CAP..1
(-7450 5250);
FORCEPROP 1 LAST LOCATION PC286
J 0
(-7400 5350);
DISPLAY 0.489362 (-7400 5350);
PAINT SKYBLUE (-7400 5350);
FORCEPROP 0 LAST $SEC 1
J 0
(-7400 5400);
DISPLAY 0.680851 (-7400 5400);
PAINT MONO (-7400 5400);
DISPLAY INVISIBLE (-7400 5400);
FORCEPROP 0 LAST CDS_SEC 1
J 0
(-7400 5400);
DISPLAY 1.021277 (-7400 5400);
DISPLAY INVISIBLE (-7400 5400);
FORCEPROP 1 LASTPIN (-7450 5350) $PN 1
J 0
(-7440 5330);
DISPLAY 0.489362 (-7440 5330);
PAINT MONO (-7440 5330);
FORCEPROP 1 LASTPIN (-7450 5150) $PN 2
J 0
(-7440 5130);
DISPLAY 0.489362 (-7440 5130);
PAINT MONO (-7440 5130);
FORCEPROP 1 LAST MATERIAL X6S
J 0
(-7400 5150);
DISPLAY 0.489362 (-7400 5150);
PAINT SKYBLUE (-7400 5150);
FORCEPROP 1 LAST TOLERANCE 10%
J 0
(-7400 5200);
DISPLAY 0.489362 (-7400 5200);
PAINT SKYBLUE (-7400 5200);
FORCEPROP 1 LAST VALUE 2.2UF
J 0
(-7400 5300);
DISPLAY 0.489362 (-7400 5300);
PAINT SKYBLUE (-7400 5300);
FORCEPROP 1 LAST PART_NUMBER CH5222KEB01
J 0
(-7400 5100);
DISPLAY 0.489362 (-7400 5100);
PAINT SKYBLUE (-7400 5100);
FORCEPROP 1 LAST VOLTAGE 10V
J 0
(-7400 5250);
DISPLAY 0.489362 (-7400 5250);
PAINT SKYBLUE (-7400 5250);
FORCEPROP 1 LAST PACK_TYPE C0402
J 0
(-7400 5050);
DISPLAY 0.489362 (-7400 5050);
PAINT SKYBLUE (-7400 5050);
FORCEPROP 2 LAST CDS_LIB pure_quanta
J 0
(-7450 5250);
DISPLAY INVISIBLE (-7450 5250);
FORCEPROP 1 LAST PATH I109
J 0
(-7400 5400);
DISPLAY 0.978723 (-7400 5400);
PAINT WHITE (-7400 5400);
DISPLAY INVISIBLE (-7400 5400);
FORCEADD UNIVERSAL_GND..1
(-7450 5050);
FORCEPROP 3 LASTPIN (-7450 5100) SIG_NAME GND\g
J 0
(-7440 5110);
DISPLAY 0.659574 (-7440 5110);
PAINT MONO (-7440 5110);
DISPLAY INVISIBLE (-7440 5110);
FORCEPROP 2 LAST CDS_LIB pure_quanta_power
J 0
(-7450 5050);
DISPLAY INVISIBLE (-7450 5050);
FORCEPROP 1 LAST PATH I110
J 0
(-7375 5050);
DISPLAY 0.872340 (-7375 5050);
PAINT AQUA (-7375 5050);
DISPLAY INVISIBLE (-7375 5050);
FORCEPROP 1 LAST HDL_POWER GND
J 1
(-7425 4975);
DISPLAY 0.872340 (-7425 4975);
PAINT GREEN (-7425 4975);
DISPLAY INVISIBLE (-7425 4975);
FORCEADD UNIVERSAL_GND..1
(-7100 5550);
FORCEPROP 3 LASTPIN (-7100 5600) SIG_NAME GND\g
J 0
(-7090 5610);
DISPLAY 0.659574 (-7090 5610);
PAINT MONO (-7090 5610);
DISPLAY INVISIBLE (-7090 5610);
FORCEPROP 2 LAST CDS_LIB pure_quanta_power
J 0
(-7100 5550);
DISPLAY INVISIBLE (-7100 5550);
FORCEPROP 1 LAST PATH I111
J 0
(-7025 5550);
DISPLAY 0.872340 (-7025 5550);
PAINT AQUA (-7025 5550);
DISPLAY INVISIBLE (-7025 5550);
FORCEPROP 1 LAST HDL_POWER GND
J 1
(-7075 5475);
DISPLAY 0.872340 (-7075 5475);
PAINT GREEN (-7075 5475);
DISPLAY INVISIBLE (-7075 5475);
FORCEADD Q_RES..2
(-7450 5800);
FORCEPROP 1 LAST LOCATION PR193
J 0
(-7405 5925);
DISPLAY 0.489362 (-7405 5925);
PAINT SKYBLUE (-7405 5925);
FORCEPROP 0 LAST $SEC 1
J 0
(-7400 5975);
DISPLAY 0.680851 (-7400 5975);
PAINT MONO (-7400 5975);
DISPLAY INVISIBLE (-7400 5975);
FORCEPROP 0 LAST CDS_SEC 1
J 0
(-7400 5975);
DISPLAY 1.021277 (-7400 5975);
DISPLAY INVISIBLE (-7400 5975);
FORCEPROP 1 LASTPIN (-7450 5900) $PN 1
J 0
(-7445 5862);
DISPLAY 0.489362 (-7445 5862);
PAINT MONO (-7445 5862);
FORCEPROP 1 LASTPIN (-7450 5700) $PN 2
J 0
(-7445 5710);
DISPLAY 0.489362 (-7445 5710);
PAINT MONO (-7445 5710);
FORCEPROP 1 LAST WATTAGE 1/16W
J 0
(-7400 5775);
DISPLAY 0.489362 (-7400 5775);
PAINT SKYBLUE (-7400 5775);
FORCEPROP 1 LAST MATERIAL CHIP
J 0
(-7400 5725);
DISPLAY 0.489362 (-7400 5725);
PAINT SKYBLUE (-7400 5725);
FORCEPROP 1 LAST TOLERANCE 1%
J 0
(-7400 5825);
DISPLAY 0.489362 (-7400 5825);
PAINT SKYBLUE (-7400 5825);
FORCEPROP 1 LAST VALUE 2.2
J 0
(-7400 5875);
DISPLAY 0.489362 (-7400 5875);
PAINT SKYBLUE (-7400 5875);
FORCEPROP 1 LAST PART_NUMBER CS-2202FB00
J 0
(-7400 5675);
DISPLAY 0.489362 (-7400 5675);
PAINT SKYBLUE (-7400 5675);
FORCEPROP 1 LAST PACK_TYPE 0402LF
J 0
(-7400 5625);
DISPLAY 0.489362 (-7400 5625);
PAINT SKYBLUE (-7400 5625);
FORCEPROP 2 LAST CDS_LIB pure_quanta
J 0
(-7450 5800);
DISPLAY INVISIBLE (-7450 5800);
FORCEPROP 1 LAST PATH I112
J 0
(-7400 5975);
DISPLAY 0.978723 (-7400 5975);
PAINT WHITE (-7400 5975);
DISPLAY INVISIBLE (-7400 5975);
FORCEADD Q_CAP..1
(-7100 5825);
FORCEPROP 1 LAST LOCATION PC288_C0P1_3
J 0
(-7050 5925);
DISPLAY 0.489362 (-7050 5925);
PAINT SKYBLUE (-7050 5925);
FORCEPROP 0 LAST $SEC 1
J 0
(-7050 5975);
DISPLAY 0.680851 (-7050 5975);
PAINT MONO (-7050 5975);
DISPLAY INVISIBLE (-7050 5975);
FORCEPROP 0 LAST CDS_SEC 1
J 0
(-7050 5975);
DISPLAY 1.021277 (-7050 5975);
DISPLAY INVISIBLE (-7050 5975);
FORCEPROP 1 LASTPIN (-7100 5925) $PN 1
J 0
(-7090 5905);
DISPLAY 0.489362 (-7090 5905);
PAINT MONO (-7090 5905);
FORCEPROP 1 LASTPIN (-7100 5725) $PN 2
J 0
(-7090 5705);
DISPLAY 0.489362 (-7090 5705);
PAINT MONO (-7090 5705);
FORCEPROP 1 LAST MATERIAL X6S
J 0
(-7050 5725);
DISPLAY 0.489362 (-7050 5725);
PAINT SKYBLUE (-7050 5725);
FORCEPROP 1 LAST TOLERANCE 10%
J 0
(-7050 5775);
DISPLAY 0.489362 (-7050 5775);
PAINT SKYBLUE (-7050 5775);
FORCEPROP 1 LAST VALUE 2.2UF
J 0
(-7050 5875);
DISPLAY 0.489362 (-7050 5875);
PAINT SKYBLUE (-7050 5875);
FORCEPROP 1 LAST PART_NUMBER CH5222KEB01
J 0
(-7050 5675);
DISPLAY 0.489362 (-7050 5675);
PAINT SKYBLUE (-7050 5675);
FORCEPROP 1 LAST VOLTAGE 10V
J 0
(-7050 5825);
DISPLAY 0.489362 (-7050 5825);
PAINT SKYBLUE (-7050 5825);
FORCEPROP 1 LAST PACK_TYPE C0402
J 0
(-7050 5625);
DISPLAY 0.489362 (-7050 5625);
PAINT SKYBLUE (-7050 5625);
FORCEPROP 2 LAST CDS_LIB pure_quanta
J 0
(-7100 5825);
DISPLAY INVISIBLE (-7100 5825);
FORCEPROP 1 LAST PATH I113
J 0
(-7050 5975);
DISPLAY 0.978723 (-7050 5975);
PAINT WHITE (-7050 5975);
DISPLAY INVISIBLE (-7050 5975);
FORCEADD VCC_CORE..1
(-7450 6200);
FORCEPROP 3 LASTPIN (-7450 6150) SIG_NAME PVDDCR_CPU0_P1_PVCC\g
J 0
(-7440 6160);
DISPLAY 0.659574 (-7440 6160);
PAINT MONO (-7440 6160);
DISPLAY INVISIBLE (-7440 6160);
FORCEPROP 1 LAST HDL_POWER PVDDCR_CPU0_P1_PVCC
J 1
(-7450 6250);
DISPLAY 0.489362 (-7450 6250);
PAINT GREEN (-7450 6250);
FORCEPROP 2 LAST CDS_LIB pure_quanta_power
J 0
(-7450 6200);
DISPLAY INVISIBLE (-7450 6200);
FORCEPROP 1 LAST PATH I114
J 0
(-7400 6225);
DISPLAY 0.872340 (-7400 6225);
PAINT AQUA (-7400 6225);
DISPLAY INVISIBLE (-7400 6225);
FORCEADD Q_CAP..1
(-7350 1950);
FORCEPROP 1 LAST LOCATION PC287
J 0
(-7300 2050);
DISPLAY 0.489362 (-7300 2050);
PAINT SKYBLUE (-7300 2050);
FORCEPROP 0 LAST $SEC 1
J 0
(-7300 2100);
DISPLAY 0.680851 (-7300 2100);
PAINT MONO (-7300 2100);
DISPLAY INVISIBLE (-7300 2100);
FORCEPROP 0 LAST CDS_SEC 1
J 0
(-7300 2100);
DISPLAY 1.021277 (-7300 2100);
DISPLAY INVISIBLE (-7300 2100);
FORCEPROP 1 LASTPIN (-7350 2050) $PN 1
J 0
(-7340 2030);
DISPLAY 0.489362 (-7340 2030);
PAINT MONO (-7340 2030);
FORCEPROP 1 LASTPIN (-7350 1850) $PN 2
J 0
(-7340 1830);
DISPLAY 0.489362 (-7340 1830);
PAINT MONO (-7340 1830);
FORCEPROP 1 LAST MATERIAL X6S
J 0
(-7300 1850);
DISPLAY 0.489362 (-7300 1850);
PAINT SKYBLUE (-7300 1850);
FORCEPROP 1 LAST TOLERANCE 10%
J 0
(-7300 1900);
DISPLAY 0.489362 (-7300 1900);
PAINT SKYBLUE (-7300 1900);
FORCEPROP 1 LAST VALUE 2.2UF
J 0
(-7300 2000);
DISPLAY 0.489362 (-7300 2000);
PAINT SKYBLUE (-7300 2000);
FORCEPROP 1 LAST PART_NUMBER CH5222KEB01
J 0
(-7300 1800);
DISPLAY 0.489362 (-7300 1800);
PAINT SKYBLUE (-7300 1800);
FORCEPROP 1 LAST VOLTAGE 10V
J 0
(-7300 1950);
DISPLAY 0.489362 (-7300 1950);
PAINT SKYBLUE (-7300 1950);
FORCEPROP 1 LAST PACK_TYPE C0402
J 0
(-7300 1750);
DISPLAY 0.489362 (-7300 1750);
PAINT SKYBLUE (-7300 1750);
FORCEPROP 2 LAST CDS_LIB pure_quanta
J 0
(-7350 1950);
DISPLAY INVISIBLE (-7350 1950);
FORCEPROP 1 LAST PATH I115
J 0
(-7300 2100);
DISPLAY 0.978723 (-7300 2100);
PAINT WHITE (-7300 2100);
DISPLAY INVISIBLE (-7300 2100);
FORCEADD UNIVERSAL_GND..1
(-7350 1750);
FORCEPROP 3 LASTPIN (-7350 1800) SIG_NAME GND\g
J 0
(-7340 1810);
DISPLAY 0.659574 (-7340 1810);
PAINT MONO (-7340 1810);
DISPLAY INVISIBLE (-7340 1810);
FORCEPROP 2 LAST CDS_LIB pure_quanta_power
J 0
(-7350 1750);
DISPLAY INVISIBLE (-7350 1750);
FORCEPROP 1 LAST PATH I116
J 0
(-7275 1750);
DISPLAY 0.872340 (-7275 1750);
PAINT AQUA (-7275 1750);
DISPLAY INVISIBLE (-7275 1750);
FORCEPROP 1 LAST HDL_POWER GND
J 1
(-7325 1675);
DISPLAY 0.872340 (-7325 1675);
PAINT GREEN (-7325 1675);
DISPLAY INVISIBLE (-7325 1675);
FORCEADD UNIVERSAL_GND..1
(-7000 2250);
FORCEPROP 3 LASTPIN (-7000 2300) SIG_NAME GND\g
J 0
(-6990 2310);
DISPLAY 0.659574 (-6990 2310);
PAINT MONO (-6990 2310);
DISPLAY INVISIBLE (-6990 2310);
FORCEPROP 2 LAST CDS_LIB pure_quanta_power
J 0
(-7000 2250);
DISPLAY INVISIBLE (-7000 2250);
FORCEPROP 1 LAST PATH I117
J 0
(-6925 2250);
DISPLAY 0.872340 (-6925 2250);
PAINT AQUA (-6925 2250);
DISPLAY INVISIBLE (-6925 2250);
FORCEPROP 1 LAST HDL_POWER GND
J 1
(-6975 2175);
DISPLAY 0.872340 (-6975 2175);
PAINT GREEN (-6975 2175);
DISPLAY INVISIBLE (-6975 2175);
FORCEADD Q_RES..2
(-7350 2500);
FORCEPROP 1 LAST LOCATION PR194
J 0
(-7305 2625);
DISPLAY 0.489362 (-7305 2625);
PAINT SKYBLUE (-7305 2625);
FORCEPROP 0 LAST $SEC 1
J 0
(-7300 2675);
DISPLAY 0.680851 (-7300 2675);
PAINT MONO (-7300 2675);
DISPLAY INVISIBLE (-7300 2675);
FORCEPROP 0 LAST CDS_SEC 1
J 0
(-7300 2675);
DISPLAY 1.021277 (-7300 2675);
DISPLAY INVISIBLE (-7300 2675);
FORCEPROP 1 LASTPIN (-7350 2600) $PN 1
J 0
(-7345 2562);
DISPLAY 0.489362 (-7345 2562);
PAINT MONO (-7345 2562);
FORCEPROP 1 LASTPIN (-7350 2400) $PN 2
J 0
(-7345 2410);
DISPLAY 0.489362 (-7345 2410);
PAINT MONO (-7345 2410);
FORCEPROP 1 LAST WATTAGE 1/16W
J 0
(-7300 2475);
DISPLAY 0.489362 (-7300 2475);
PAINT SKYBLUE (-7300 2475);
FORCEPROP 1 LAST MATERIAL CHIP
J 0
(-7300 2425);
DISPLAY 0.489362 (-7300 2425);
PAINT SKYBLUE (-7300 2425);
FORCEPROP 1 LAST TOLERANCE 1%
J 0
(-7300 2525);
DISPLAY 0.489362 (-7300 2525);
PAINT SKYBLUE (-7300 2525);
FORCEPROP 1 LAST VALUE 2.2
J 0
(-7300 2575);
DISPLAY 0.489362 (-7300 2575);
PAINT SKYBLUE (-7300 2575);
FORCEPROP 1 LAST PART_NUMBER CS-2202FB00
J 0
(-7300 2375);
DISPLAY 0.489362 (-7300 2375);
PAINT SKYBLUE (-7300 2375);
FORCEPROP 1 LAST PACK_TYPE 0402LF
J 0
(-7300 2325);
DISPLAY 0.489362 (-7300 2325);
PAINT SKYBLUE (-7300 2325);
FORCEPROP 2 LAST CDS_LIB pure_quanta
J 0
(-7350 2500);
DISPLAY INVISIBLE (-7350 2500);
FORCEPROP 1 LAST PATH I118
J 0
(-7300 2675);
DISPLAY 0.978723 (-7300 2675);
PAINT WHITE (-7300 2675);
DISPLAY INVISIBLE (-7300 2675);
FORCEADD Q_CAP..1
(-7000 2525);
FORCEPROP 1 LAST LOCATION PC289_C0P1_4
J 0
(-6950 2625);
DISPLAY 0.489362 (-6950 2625);
PAINT SKYBLUE (-6950 2625);
FORCEPROP 0 LAST $SEC 1
J 0
(-6950 2675);
DISPLAY 0.680851 (-6950 2675);
PAINT MONO (-6950 2675);
DISPLAY INVISIBLE (-6950 2675);
FORCEPROP 0 LAST CDS_SEC 1
J 0
(-6950 2675);
DISPLAY 1.021277 (-6950 2675);
DISPLAY INVISIBLE (-6950 2675);
FORCEPROP 1 LASTPIN (-7000 2625) $PN 1
J 0
(-6990 2605);
DISPLAY 0.489362 (-6990 2605);
PAINT MONO (-6990 2605);
FORCEPROP 1 LASTPIN (-7000 2425) $PN 2
J 0
(-6990 2405);
DISPLAY 0.489362 (-6990 2405);
PAINT MONO (-6990 2405);
FORCEPROP 1 LAST MATERIAL X6S
J 0
(-6950 2425);
DISPLAY 0.489362 (-6950 2425);
PAINT SKYBLUE (-6950 2425);
FORCEPROP 1 LAST TOLERANCE 10%
J 0
(-6950 2475);
DISPLAY 0.489362 (-6950 2475);
PAINT SKYBLUE (-6950 2475);
FORCEPROP 1 LAST VALUE 2.2UF
J 0
(-6950 2575);
DISPLAY 0.489362 (-6950 2575);
PAINT SKYBLUE (-6950 2575);
FORCEPROP 1 LAST PART_NUMBER CH5222KEB01
J 0
(-6950 2375);
DISPLAY 0.489362 (-6950 2375);
PAINT SKYBLUE (-6950 2375);
FORCEPROP 1 LAST VOLTAGE 10V
J 0
(-6950 2525);
DISPLAY 0.489362 (-6950 2525);
PAINT SKYBLUE (-6950 2525);
FORCEPROP 1 LAST PACK_TYPE C0402
J 0
(-6950 2325);
DISPLAY 0.489362 (-6950 2325);
PAINT SKYBLUE (-6950 2325);
FORCEPROP 2 LAST CDS_LIB pure_quanta
J 0
(-7000 2525);
DISPLAY INVISIBLE (-7000 2525);
FORCEPROP 1 LAST PATH I119
J 0
(-6950 2675);
DISPLAY 0.978723 (-6950 2675);
PAINT WHITE (-6950 2675);
DISPLAY INVISIBLE (-6950 2675);
FORCEADD VCC_CORE..1
(-7350 2900);
FORCEPROP 3 LASTPIN (-7350 2850) SIG_NAME PVDDCR_CPU0_P1_PVCC\g
J 0
(-7340 2860);
DISPLAY 0.659574 (-7340 2860);
PAINT MONO (-7340 2860);
DISPLAY INVISIBLE (-7340 2860);
FORCEPROP 1 LAST HDL_POWER PVDDCR_CPU0_P1_PVCC
J 1
(-7350 2950);
DISPLAY 0.489362 (-7350 2950);
PAINT GREEN (-7350 2950);
FORCEPROP 2 LAST CDS_LIB pure_quanta_power
J 0
(-7350 2900);
DISPLAY INVISIBLE (-7350 2900);
FORCEPROP 1 LAST PATH I120
J 0
(-7300 2925);
DISPLAY 0.872340 (-7300 2925);
PAINT AQUA (-7300 2925);
DISPLAY INVISIBLE (-7300 2925);
FORCEADD UNIVERSAL_GND..1
(-4450 3975);
FORCEPROP 3 LASTPIN (-4450 4025) SIG_NAME GND\g
J 0
(-4440 4035);
DISPLAY 0.659574 (-4440 4035);
PAINT MONO (-4440 4035);
DISPLAY INVISIBLE (-4440 4035);
FORCEPROP 2 LAST CDS_LIB pure_quanta_power
J 0
(-4450 3975);
DISPLAY INVISIBLE (-4450 3975);
FORCEPROP 1 LAST PATH I121
J 0
(-4375 3975);
DISPLAY 0.872340 (-4375 3975);
PAINT AQUA (-4375 3975);
DISPLAY INVISIBLE (-4375 3975);
FORCEPROP 1 LAST HDL_POWER GND
J 1
(-4425 3900);
DISPLAY 0.872340 (-4425 3900);
PAINT GREEN (-4425 3900);
DISPLAY INVISIBLE (-4425 3900);
FORCEADD Q_RES..2
(-4450 4200);
FORCEPROP 1 LAST LOCATION PR522
J 0
(-4405 4325);
DISPLAY 0.489362 (-4405 4325);
PAINT SKYBLUE (-4405 4325);
FORCEPROP 0 LAST $SEC 1
J 0
(-4400 4375);
DISPLAY 0.680851 (-4400 4375);
PAINT MONO (-4400 4375);
DISPLAY INVISIBLE (-4400 4375);
FORCEPROP 0 LAST CDS_SEC 1
J 0
(-4400 4375);
DISPLAY 1.021277 (-4400 4375);
DISPLAY INVISIBLE (-4400 4375);
FORCEPROP 1 LASTPIN (-4450 4300) $PN 1
J 0
(-4445 4262);
DISPLAY 0.489362 (-4445 4262);
PAINT MONO (-4445 4262);
FORCEPROP 1 LASTPIN (-4450 4100) $PN 2
J 0
(-4445 4110);
DISPLAY 0.489362 (-4445 4110);
PAINT MONO (-4445 4110);
FORCEPROP 1 LAST WATTAGE 1/8W
J 0
(-4410 4175);
DISPLAY 0.489362 (-4410 4175);
PAINT SKYBLUE (-4410 4175);
FORCEPROP 1 LAST MATERIAL EMPTY
J 0
(-4410 4125);
DISPLAY 0.489362 (-4410 4125);
PAINT RED (-4410 4125);
FORCEPROP 1 LAST TOLERANCE 1%
J 0
(-4405 4225);
DISPLAY 0.489362 (-4405 4225);
PAINT SKYBLUE (-4405 4225);
FORCEPROP 1 LAST VALUE 1.5
J 0
(-4405 4275);
DISPLAY 0.489362 (-4405 4275);
PAINT SKYBLUE (-4405 4275);
FORCEPROP 1 LAST PART_NUMBER CS-1504FB00
J 0
(-4410 4075);
DISPLAY 0.489362 (-4410 4075);
PAINT SKYBLUE (-4410 4075);
FORCEPROP 1 LAST PACK_TYPE 0402LF
J 0
(-4410 4025);
DISPLAY 0.489362 (-4410 4025);
PAINT SKYBLUE (-4410 4025);
FORCEPROP 2 LAST CDS_LIB pure_quanta
J 0
(-4450 4200);
DISPLAY INVISIBLE (-4450 4200);
FORCEPROP 1 LAST PATH I122
J 0
(-4400 4375);
DISPLAY 0.978723 (-4400 4375);
PAINT WHITE (-4400 4375);
DISPLAY INVISIBLE (-4400 4375);
FORCEADD Q_CAP..1
(-4450 4700);
FORCEPROP 1 LAST LOCATION PC316
J 0
(-4400 4800);
DISPLAY 0.489362 (-4400 4800);
PAINT SKYBLUE (-4400 4800);
FORCEPROP 0 LAST $SEC 1
J 0
(-4400 4850);
DISPLAY 0.680851 (-4400 4850);
PAINT MONO (-4400 4850);
DISPLAY INVISIBLE (-4400 4850);
FORCEPROP 0 LAST CDS_SEC 1
J 0
(-4400 4850);
DISPLAY 1.021277 (-4400 4850);
DISPLAY INVISIBLE (-4400 4850);
FORCEPROP 1 LASTPIN (-4450 4800) $PN 1
J 0
(-4440 4780);
DISPLAY 0.489362 (-4440 4780);
PAINT MONO (-4440 4780);
FORCEPROP 1 LASTPIN (-4450 4600) $PN 2
J 0
(-4440 4580);
DISPLAY 0.489362 (-4440 4580);
PAINT MONO (-4440 4580);
FORCEPROP 1 LAST MATERIAL EMPTY
J 0
(-4400 4600);
DISPLAY 0.489362 (-4400 4600);
PAINT RED (-4400 4600);
FORCEPROP 1 LAST TOLERANCE 10%
J 0
(-4400 4650);
DISPLAY 0.489362 (-4400 4650);
PAINT SKYBLUE (-4400 4650);
FORCEPROP 1 LAST VALUE 560PF
J 0
(-4400 4750);
DISPLAY 0.489362 (-4400 4750);
PAINT SKYBLUE (-4400 4750);
FORCEPROP 1 LAST PART_NUMBER CH1566K1B09
J 0
(-4400 4550);
DISPLAY 0.489362 (-4400 4550);
PAINT SKYBLUE (-4400 4550);
FORCEPROP 1 LAST VOLTAGE 50V
J 0
(-4400 4700);
DISPLAY 0.489362 (-4400 4700);
PAINT SKYBLUE (-4400 4700);
FORCEPROP 1 LAST PACK_TYPE C0402
J 0
(-4400 4500);
DISPLAY 0.489362 (-4400 4500);
PAINT SKYBLUE (-4400 4500);
FORCEPROP 2 LAST CDS_LIB pure_quanta
J 0
(-4450 4700);
DISPLAY INVISIBLE (-4450 4700);
FORCEPROP 1 LAST PATH I123
J 0
(-4400 4850);
DISPLAY 0.978723 (-4400 4850);
PAINT WHITE (-4400 4850);
DISPLAY INVISIBLE (-4400 4850);
FORCEADD UNIVERSAL_GND..1
(-4450 675);
FORCEPROP 3 LASTPIN (-4450 725) SIG_NAME GND\g
J 0
(-4440 735);
DISPLAY 0.659574 (-4440 735);
PAINT MONO (-4440 735);
DISPLAY INVISIBLE (-4440 735);
FORCEPROP 2 LAST CDS_LIB pure_quanta_power
J 0
(-4450 675);
DISPLAY INVISIBLE (-4450 675);
FORCEPROP 1 LAST PATH I124
J 0
(-4375 675);
DISPLAY 0.872340 (-4375 675);
PAINT AQUA (-4375 675);
DISPLAY INVISIBLE (-4375 675);
FORCEPROP 1 LAST HDL_POWER GND
J 1
(-4425 600);
DISPLAY 0.872340 (-4425 600);
PAINT GREEN (-4425 600);
DISPLAY INVISIBLE (-4425 600);
FORCEADD Q_RES..2
(-4450 900);
FORCEPROP 1 LAST LOCATION PR523
J 0
(-4405 1025);
DISPLAY 0.489362 (-4405 1025);
PAINT SKYBLUE (-4405 1025);
FORCEPROP 0 LAST $SEC 1
J 0
(-4400 1075);
DISPLAY 0.680851 (-4400 1075);
PAINT MONO (-4400 1075);
DISPLAY INVISIBLE (-4400 1075);
FORCEPROP 0 LAST CDS_SEC 1
J 0
(-4400 1075);
DISPLAY 1.021277 (-4400 1075);
DISPLAY INVISIBLE (-4400 1075);
FORCEPROP 1 LASTPIN (-4450 1000) $PN 1
J 0
(-4445 962);
DISPLAY 0.489362 (-4445 962);
PAINT MONO (-4445 962);
FORCEPROP 1 LASTPIN (-4450 800) $PN 2
J 0
(-4445 810);
DISPLAY 0.489362 (-4445 810);
PAINT MONO (-4445 810);
FORCEPROP 1 LAST WATTAGE 1/8W
J 0
(-4410 875);
DISPLAY 0.489362 (-4410 875);
PAINT SKYBLUE (-4410 875);
FORCEPROP 1 LAST MATERIAL EMPTY
J 0
(-4410 825);
DISPLAY 0.489362 (-4410 825);
PAINT RED (-4410 825);
FORCEPROP 1 LAST TOLERANCE 1%
J 0
(-4405 925);
DISPLAY 0.489362 (-4405 925);
PAINT SKYBLUE (-4405 925);
FORCEPROP 1 LAST VALUE 1.5
J 0
(-4405 975);
DISPLAY 0.489362 (-4405 975);
PAINT SKYBLUE (-4405 975);
FORCEPROP 1 LAST PART_NUMBER CS-1504FB00
J 0
(-4410 775);
DISPLAY 0.489362 (-4410 775);
PAINT SKYBLUE (-4410 775);
FORCEPROP 1 LAST PACK_TYPE 0402LF
J 0
(-4410 725);
DISPLAY 0.489362 (-4410 725);
PAINT SKYBLUE (-4410 725);
FORCEPROP 2 LAST CDS_LIB pure_quanta
J 0
(-4450 900);
DISPLAY INVISIBLE (-4450 900);
FORCEPROP 1 LAST PATH I125
J 0
(-4400 1075);
DISPLAY 0.978723 (-4400 1075);
PAINT WHITE (-4400 1075);
DISPLAY INVISIBLE (-4400 1075);
FORCEADD Q_CAP..1
(-4450 1400);
FORCEPROP 1 LAST LOCATION PC317
J 0
(-4400 1500);
DISPLAY 0.489362 (-4400 1500);
PAINT SKYBLUE (-4400 1500);
FORCEPROP 0 LAST $SEC 1
J 0
(-4400 1550);
DISPLAY 0.680851 (-4400 1550);
PAINT MONO (-4400 1550);
DISPLAY INVISIBLE (-4400 1550);
FORCEPROP 0 LAST CDS_SEC 1
J 0
(-4400 1550);
DISPLAY 1.021277 (-4400 1550);
DISPLAY INVISIBLE (-4400 1550);
FORCEPROP 1 LASTPIN (-4450 1500) $PN 1
J 0
(-4440 1480);
DISPLAY 0.489362 (-4440 1480);
PAINT MONO (-4440 1480);
FORCEPROP 1 LASTPIN (-4450 1300) $PN 2
J 0
(-4440 1280);
DISPLAY 0.489362 (-4440 1280);
PAINT MONO (-4440 1280);
FORCEPROP 1 LAST MATERIAL EMPTY
J 0
(-4400 1300);
DISPLAY 0.489362 (-4400 1300);
PAINT RED (-4400 1300);
FORCEPROP 1 LAST TOLERANCE 10%
J 0
(-4400 1350);
DISPLAY 0.489362 (-4400 1350);
PAINT SKYBLUE (-4400 1350);
FORCEPROP 1 LAST VALUE 560PF
J 0
(-4400 1450);
DISPLAY 0.489362 (-4400 1450);
PAINT SKYBLUE (-4400 1450);
FORCEPROP 1 LAST PART_NUMBER CH1566K1B09
J 0
(-4400 1250);
DISPLAY 0.489362 (-4400 1250);
PAINT SKYBLUE (-4400 1250);
FORCEPROP 1 LAST VOLTAGE 50V
J 0
(-4400 1400);
DISPLAY 0.489362 (-4400 1400);
PAINT SKYBLUE (-4400 1400);
FORCEPROP 1 LAST PACK_TYPE C0402
J 0
(-4400 1200);
DISPLAY 0.489362 (-4400 1200);
PAINT SKYBLUE (-4400 1200);
FORCEPROP 2 LAST CDS_LIB pure_quanta
J 0
(-4450 1400);
DISPLAY INVISIBLE (-4450 1400);
FORCEPROP 1 LAST PATH I126
J 0
(-4400 1550);
DISPLAY 0.978723 (-4400 1550);
PAINT WHITE (-4400 1550);
DISPLAY INVISIBLE (-4400 1550);
FORCEADD UNIVERSAL_GND..1
(-1725 1225);
FORCEPROP 3 LASTPIN (-1725 1275) SIG_NAME GND\g
J 0
(-1715 1285);
DISPLAY 0.659574 (-1715 1285);
PAINT MONO (-1715 1285);
DISPLAY INVISIBLE (-1715 1285);
FORCEPROP 2 LAST CDS_LIB pure_quanta_power
J 0
(-1725 1225);
DISPLAY INVISIBLE (-1725 1225);
FORCEPROP 1 LAST PATH I127
J 0
(-1650 1225);
DISPLAY 0.872340 (-1650 1225);
PAINT AQUA (-1650 1225);
DISPLAY INVISIBLE (-1650 1225);
FORCEPROP 1 LAST HDL_POWER GND
J 1
(-1700 1150);
DISPLAY 0.872340 (-1700 1150);
PAINT GREEN (-1700 1150);
DISPLAY INVISIBLE (-1700 1150);
FORCEADD UNIVERSAL_GND..1
(-5400 4125);
FORCEPROP 3 LASTPIN (-5400 4175) SIG_NAME GND\g
J 0
(-5390 4185);
DISPLAY 0.659574 (-5390 4185);
PAINT MONO (-5390 4185);
DISPLAY INVISIBLE (-5390 4185);
FORCEPROP 2 LAST CDS_LIB pure_quanta_power
J 0
(-5400 4125);
DISPLAY INVISIBLE (-5400 4125);
FORCEPROP 1 LAST PATH I15
J 0
(-5325 4125);
DISPLAY 0.872340 (-5325 4125);
PAINT AQUA (-5325 4125);
DISPLAY INVISIBLE (-5325 4125);
FORCEPROP 1 LAST HDL_POWER GND
J 1
(-5375 4050);
DISPLAY 0.872340 (-5375 4050);
PAINT GREEN (-5375 4050);
DISPLAY INVISIBLE (-5375 4050);
FORCEADD Q_RES..1
(-4175 3800);
FORCEPROP 1 LAST LOCATION PR199
J 0
(-4200 3850);
DISPLAY 0.489362 (-4200 3850);
PAINT SKYBLUE (-4200 3850);
FORCEPROP 0 LAST $SEC 1
J 0
(-4175 3875);
DISPLAY 0.680851 (-4175 3875);
PAINT MONO (-4175 3875);
DISPLAY INVISIBLE (-4175 3875);
FORCEPROP 0 LAST CDS_SEC 1
J 0
(-4175 3875);
DISPLAY 1.021277 (-4175 3875);
DISPLAY INVISIBLE (-4175 3875);
FORCEPROP 1 LASTPIN (-4275 3800) $PN 1
J 0
(-4263 3812);
DISPLAY 0.489362 (-4263 3812);
PAINT MONO (-4263 3812);
FORCEPROP 1 LASTPIN (-4075 3800) $PN 2
J 0
(-4113 3812);
DISPLAY 0.489362 (-4113 3812);
PAINT MONO (-4113 3812);
FORCEPROP 1 LAST WATTAGE 1/16W
J 0
(-4075 3750);
DISPLAY 0.489362 (-4075 3750);
PAINT SKYBLUE (-4075 3750);
FORCEPROP 1 LAST MATERIAL CHIP
J 0
(-4425 3700);
DISPLAY 0.489362 (-4425 3700);
PAINT SKYBLUE (-4425 3700);
FORCEPROP 1 LAST TOLERANCE 5%
J 0
(-4050 3825);
DISPLAY 0.489362 (-4050 3825);
PAINT SKYBLUE (-4050 3825);
FORCEPROP 1 LAST VALUE 0
J 2
(-4300 3825);
DISPLAY 0.489362 (-4300 3825);
PAINT SKYBLUE (-4300 3825);
FORCEPROP 1 LAST PART_NUMBER CS00002JB38
J 0
(-4425 3750);
DISPLAY 0.489362 (-4425 3750);
PAINT SKYBLUE (-4425 3750);
FORCEPROP 1 LAST PACK_TYPE 0402LF
J 0
(-4075 3700);
DISPLAY 0.489362 (-4075 3700);
PAINT SKYBLUE (-4075 3700);
FORCEPROP 2 LAST CDS_LIB pure_quanta
J 0
(-4175 3800);
DISPLAY INVISIBLE (-4175 3800);
FORCEPROP 1 LAST PATH I16
J 0
(-4225 3950);
DISPLAY 0.978723 (-4225 3950);
PAINT WHITE (-4225 3950);
DISPLAY INVISIBLE (-4225 3950);
FORCEADD Q_RES..1
(-4575 5250);
FORCEPROP 1 LAST LOCATION PR197
J 0
(-4625 5300);
DISPLAY 0.489362 (-4625 5300);
PAINT SKYBLUE (-4625 5300);
FORCEPROP 0 LAST $SEC 1
J 0
(-4550 5325);
DISPLAY 0.680851 (-4550 5325);
PAINT MONO (-4550 5325);
DISPLAY INVISIBLE (-4550 5325);
FORCEPROP 0 LAST CDS_SEC 1
J 0
(-4550 5325);
DISPLAY 1.021277 (-4550 5325);
DISPLAY INVISIBLE (-4550 5325);
FORCEPROP 1 LASTPIN (-4675 5250) $PN 1
J 0
(-4663 5262);
DISPLAY 0.489362 (-4663 5262);
PAINT MONO (-4663 5262);
FORCEPROP 1 LASTPIN (-4475 5250) $PN 2
J 0
(-4513 5262);
DISPLAY 0.489362 (-4513 5262);
PAINT MONO (-4513 5262);
FORCEPROP 1 LAST PACK_TYPE 0402LF
J 0
(-4475 5150);
DISPLAY 0.489362 (-4475 5150);
PAINT SKYBLUE (-4475 5150);
FORCEPROP 1 LAST TOLERANCE 1%
J 0
(-4450 5275);
DISPLAY 0.489362 (-4450 5275);
PAINT SKYBLUE (-4450 5275);
FORCEPROP 1 LAST MATERIAL CHIP
J 0
(-4825 5150);
DISPLAY 0.489362 (-4825 5150);
PAINT SKYBLUE (-4825 5150);
FORCEPROP 1 LAST WATTAGE 1/16W
J 0
(-4475 5200);
DISPLAY 0.489362 (-4475 5200);
PAINT SKYBLUE (-4475 5200);
FORCEPROP 1 LAST VALUE 4.7
J 2
(-4700 5275);
DISPLAY 0.489362 (-4700 5275);
PAINT SKYBLUE (-4700 5275);
FORCEPROP 1 LAST PART_NUMBER CS-4702FB19
J 0
(-4825 5200);
DISPLAY 0.489362 (-4825 5200);
PAINT SKYBLUE (-4825 5200);
FORCEPROP 1 LAST PATH I18
J 0
(-4625 5400);
DISPLAY 0.978723 (-4625 5400);
PAINT WHITE (-4625 5400);
DISPLAY INVISIBLE (-4625 5400);
FORCEPROP 2 LAST CDS_LIB pure_quanta
J 0
(-4575 5250);
DISPLAY INVISIBLE (-4575 5250);
FORCEADD Q_CAP..1
(-4975 5800);
FORCEPROP 1 LAST LOCATION PC292_3
J 0
(-4925 5900);
DISPLAY 0.489362 (-4925 5900);
PAINT SKYBLUE (-4925 5900);
FORCEPROP 0 LAST $SEC 1
J 0
(-4925 5925);
DISPLAY 0.680851 (-4925 5925);
PAINT MONO (-4925 5925);
DISPLAY INVISIBLE (-4925 5925);
FORCEPROP 0 LAST CDS_SEC 1
J 0
(-4925 5925);
DISPLAY 1.021277 (-4925 5925);
DISPLAY INVISIBLE (-4925 5925);
FORCEPROP 1 LASTPIN (-4975 5900) $PN 1
J 0
(-4965 5880);
DISPLAY 0.489362 (-4965 5880);
PAINT MONO (-4965 5880);
FORCEPROP 1 LASTPIN (-4975 5700) $PN 2
J 0
(-4965 5680);
DISPLAY 0.489362 (-4965 5680);
PAINT MONO (-4965 5680);
FORCEPROP 1 LAST MATERIAL X6S
J 0
(-4925 5700);
DISPLAY 0.489362 (-4925 5700);
PAINT SKYBLUE (-4925 5700);
FORCEPROP 1 LAST TOLERANCE 10%
J 0
(-4925 5750);
DISPLAY 0.489362 (-4925 5750);
PAINT SKYBLUE (-4925 5750);
FORCEPROP 1 LAST VALUE 1UF
J 0
(-4925 5850);
DISPLAY 0.489362 (-4925 5850);
PAINT SKYBLUE (-4925 5850);
FORCEPROP 1 LAST PART_NUMBER CH5104KEB02
J 0
(-4925 5650);
DISPLAY 0.489362 (-4925 5650);
PAINT SKYBLUE (-4925 5650);
FORCEPROP 1 LAST VOLTAGE 25V
J 0
(-4925 5800);
DISPLAY 0.489362 (-4925 5800);
PAINT SKYBLUE (-4925 5800);
FORCEPROP 1 LAST PACK_TYPE C0402
J 0
(-4925 5600);
DISPLAY 0.489362 (-4925 5600);
PAINT SKYBLUE (-4925 5600);
FORCEPROP 2 LAST CDS_LIB pure_quanta
J 0
(-4975 5800);
DISPLAY INVISIBLE (-4975 5800);
FORCEPROP 1 LAST PATH I19
J 0
(-4925 5950);
DISPLAY 0.978723 (-4925 5950);
PAINT WHITE (-4925 5950);
DISPLAY INVISIBLE (-4925 5950);
FORCEADD OFFPAGE..1
(-8000 4800);
FORCEPROP 2 LAST $XR5 192 
J 0
(-8852 4800);
DISPLAY 0.638298 (-8852 4800);
PAINT MONO (-8852 4800);
FORCEPROP 2 LAST $XR4 191 
J 0
(-8732 4800);
DISPLAY 0.638298 (-8732 4800);
PAINT MONO (-8732 4800);
FORCEPROP 2 LAST $XR3 189 
J 0
(-8612 4800);
DISPLAY 0.638298 (-8612 4800);
PAINT MONO (-8612 4800);
FORCEPROP 2 LAST $XR2 188 
J 0
(-8492 4800);
DISPLAY 0.638298 (-8492 4800);
PAINT MONO (-8492 4800);
FORCEPROP 2 LAST $XR1 187 
J 0
(-8372 4800);
DISPLAY 0.638298 (-8372 4800);
PAINT MONO (-8372 4800);
FORCEPROP 2 LAST $XR0 186 
J 0
(-8252 4800);
DISPLAY 0.638298 (-8252 4800);
PAINT MONO (-8252 4800);
FORCEPROP 2 LAST PATH I2
J 0
(-7950 4875);
DISPLAY 1.021277 (-7950 4875);
DISPLAY INVISIBLE (-7950 4875);
FORCEPROP 1 LAST COMMENT_BODY TRUE
J 0
(-7875 4700);
DISPLAY 0.872340 (-7875 4700);
PAINT GREEN (-7875 4700);
DISPLAY INVISIBLE (-7875 4700);
FORCEPROP 1 LAST OFFPAGE TRUE
J 0
(-7675 4675);
DISPLAY 0.872340 (-7675 4675);
PAINT GREEN (-7675 4675);
DISPLAY INVISIBLE (-7675 4675);
FORCEPROP 2 LAST CDS_LIB standard
J 0
(-8000 4800);
DISPLAY INVISIBLE (-8000 4800);
FORCEADD Q_CAP..1
(-4650 5800);
FORCEPROP 1 LAST LOCATION PC294_3
J 0
(-4600 5900);
DISPLAY 0.489362 (-4600 5900);
PAINT SKYBLUE (-4600 5900);
FORCEPROP 0 LAST $SEC 1
J 0
(-4600 5925);
DISPLAY 0.680851 (-4600 5925);
PAINT MONO (-4600 5925);
DISPLAY INVISIBLE (-4600 5925);
FORCEPROP 0 LAST CDS_SEC 1
J 0
(-4600 5925);
DISPLAY 1.021277 (-4600 5925);
DISPLAY INVISIBLE (-4600 5925);
FORCEPROP 1 LASTPIN (-4650 5900) $PN 1
J 0
(-4640 5880);
DISPLAY 0.489362 (-4640 5880);
PAINT MONO (-4640 5880);
FORCEPROP 1 LASTPIN (-4650 5700) $PN 2
J 0
(-4640 5680);
DISPLAY 0.489362 (-4640 5680);
PAINT MONO (-4640 5680);
FORCEPROP 1 LAST MATERIAL X6S
J 0
(-4600 5700);
DISPLAY 0.489362 (-4600 5700);
PAINT SKYBLUE (-4600 5700);
FORCEPROP 1 LAST TOLERANCE 10%
J 0
(-4600 5750);
DISPLAY 0.489362 (-4600 5750);
PAINT SKYBLUE (-4600 5750);
FORCEPROP 1 LAST VALUE 10UF
J 0
(-4600 5850);
DISPLAY 0.489362 (-4600 5850);
PAINT SKYBLUE (-4600 5850);
FORCEPROP 1 LAST PART_NUMBER CH6104KEA00
J 0
(-4600 5650);
DISPLAY 0.489362 (-4600 5650);
PAINT SKYBLUE (-4600 5650);
FORCEPROP 1 LAST VOLTAGE 25V
J 0
(-4600 5800);
DISPLAY 0.489362 (-4600 5800);
PAINT SKYBLUE (-4600 5800);
FORCEPROP 1 LAST PACK_TYPE C0805
J 0
(-4600 5600);
DISPLAY 0.489362 (-4600 5600);
PAINT SKYBLUE (-4600 5600);
FORCEPROP 2 LAST CDS_LIB pure_quanta
J 0
(-4650 5800);
DISPLAY INVISIBLE (-4650 5800);
FORCEPROP 1 LAST PATH I20
J 0
(-4600 5950);
DISPLAY 0.978723 (-4600 5950);
PAINT WHITE (-4600 5950);
DISPLAY INVISIBLE (-4600 5950);
FORCEADD Q_CAP..1
(-4325 5800);
FORCEPROP 1 LAST LOCATION PC296_3
J 0
(-4275 5900);
DISPLAY 0.489362 (-4275 5900);
PAINT SKYBLUE (-4275 5900);
FORCEPROP 0 LAST $SEC 1
J 0
(-4275 5925);
DISPLAY 0.680851 (-4275 5925);
PAINT MONO (-4275 5925);
DISPLAY INVISIBLE (-4275 5925);
FORCEPROP 0 LAST CDS_SEC 1
J 0
(-4275 5925);
DISPLAY 1.021277 (-4275 5925);
DISPLAY INVISIBLE (-4275 5925);
FORCEPROP 1 LASTPIN (-4325 5900) $PN 1
J 0
(-4315 5880);
DISPLAY 0.489362 (-4315 5880);
PAINT MONO (-4315 5880);
FORCEPROP 1 LASTPIN (-4325 5700) $PN 2
J 0
(-4315 5680);
DISPLAY 0.489362 (-4315 5680);
PAINT MONO (-4315 5680);
FORCEPROP 1 LAST MATERIAL X6S
J 0
(-4275 5700);
DISPLAY 0.489362 (-4275 5700);
PAINT SKYBLUE (-4275 5700);
FORCEPROP 1 LAST TOLERANCE 10%
J 0
(-4275 5750);
DISPLAY 0.489362 (-4275 5750);
PAINT SKYBLUE (-4275 5750);
FORCEPROP 1 LAST VALUE 10UF
J 0
(-4275 5850);
DISPLAY 0.489362 (-4275 5850);
PAINT SKYBLUE (-4275 5850);
FORCEPROP 1 LAST PART_NUMBER CH6104KEA00
J 0
(-4275 5650);
DISPLAY 0.489362 (-4275 5650);
PAINT SKYBLUE (-4275 5650);
FORCEPROP 1 LAST VOLTAGE 25V
J 0
(-4275 5800);
DISPLAY 0.489362 (-4275 5800);
PAINT SKYBLUE (-4275 5800);
FORCEPROP 1 LAST PACK_TYPE C0805
J 0
(-4275 5600);
DISPLAY 0.489362 (-4275 5600);
PAINT SKYBLUE (-4275 5600);
FORCEPROP 2 LAST CDS_LIB pure_quanta
J 0
(-4325 5800);
DISPLAY INVISIBLE (-4325 5800);
FORCEPROP 1 LAST PATH I21
J 0
(-4275 5950);
DISPLAY 0.978723 (-4275 5950);
PAINT WHITE (-4275 5950);
DISPLAY INVISIBLE (-4275 5950);
FORCEADD OFFPAGE..3
R 2
(-3600 4650);
FORCEPROP 2 LAST $XR0 187 
J 0
(-3880 4650);
DISPLAY 0.638298 (-3880 4650);
PAINT MONO (-3880 4650);
FORCEPROP 2 LAST PATH I22
J 0
(-3550 4725);
DISPLAY 1.021277 (-3550 4725);
DISPLAY INVISIBLE (-3550 4725);
FORCEPROP 1 LAST COMMENT_BODY TRUE
J 2
(-3550 4550);
DISPLAY 0.872340 (-3550 4550);
PAINT GREEN (-3550 4550);
DISPLAY INVISIBLE (-3550 4550);
FORCEPROP 1 LAST OFFPAGE TRUE
J 2
(-3925 4525);
DISPLAY 0.872340 (-3925 4525);
PAINT GREEN (-3925 4525);
DISPLAY INVISIBLE (-3925 4525);
FORCEPROP 2 LAST CDS_LIB standard
J 2
(-3600 4650);
DISPLAY INVISIBLE (-3600 4650);
FORCEADD Q_INDUCTOR4P_14..1
(-2650 4775);
FORCEPROP 1 LAST LOCATION PL31
J 0
(-2875 5030);
DISPLAY 0.489362 (-2875 5030);
PAINT SKYBLUE (-2875 5030);
FORCEPROP 0 LAST $SEC 1
J 0
(-2875 5175);
DISPLAY 0.680851 (-2875 5175);
PAINT MONO (-2875 5175);
DISPLAY INVISIBLE (-2875 5175);
FORCEPROP 0 LAST CDS_SEC 1
J 0
(-2875 5175);
DISPLAY 1.021277 (-2875 5175);
DISPLAY INVISIBLE (-2875 5175);
FORCEPROP 0 LASTPIN (-3050 4900) $PN 1
J 2
(-3060 4910);
DISPLAY 0.489362 (-3060 4910);
PAINT MONO (-3060 4910);
FORCEPROP 0 LASTPIN (-3050 4650) $PN 2
J 2
(-3060 4660);
DISPLAY 0.489362 (-3060 4660);
PAINT MONO (-3060 4660);
FORCEPROP 0 LASTPIN (-2250 4650) $PN 3
J 0
(-2240 4660);
DISPLAY 0.489362 (-2240 4660);
PAINT MONO (-2240 4660);
FORCEPROP 0 LASTPIN (-2250 4900) $PN 4
J 0
(-2240 4910);
DISPLAY 0.489362 (-2240 4910);
PAINT MONO (-2240 4910);
FORCEPROP 2 LAST PART_TYPE SMLF
J 0
(-2875 5125);
DISPLAY 1.021277 (-2875 5125);
FORCEPROP 1 LAST MATERIAL IND
J 0
(-2875 4985);
DISPLAY 0.489362 (-2875 4985);
PAINT SKYBLUE (-2875 4985);
FORCEPROP 2 LAST VALUE 150NH
J 0
(-2875 5075);
DISPLAY 0.489362 (-2875 5075);
PAINT SKYBLUE (-2875 5075);
FORCEPROP 1 LAST PART_NUMBER CV+15^0TZ04
J 0
(-2875 4935);
DISPLAY 0.489362 (-2875 4935);
PAINT SKYBLUE (-2875 4935);
FORCEPROP 2 LAST CDS_LIB pure_quanta
J 0
(-2650 4775);
DISPLAY INVISIBLE (-2650 4775);
FORCEPROP 1 LAST NEEDS_NO_SIZE TRUE
J 0
(-2650 4775);
DISPLAY 0.468085 (-2650 4775);
PAINT GREEN (-2650 4775);
DISPLAY INVISIBLE (-2650 4775);
FORCEPROP 1 LAST PATH I23
J 0
(-2450 4930);
DISPLAY 0.723404 (-2450 4930);
PAINT GREEN (-2450 4930);
DISPLAY INVISIBLE (-2450 4930);
FORCEADD Q_CAP..1
(-3600 5125);
FORCEPROP 1 LAST LOCATION PC300
J 0
(-3550 5250);
DISPLAY 0.489362 (-3550 5250);
PAINT SKYBLUE (-3550 5250);
FORCEPROP 0 LAST $SEC 1
J 0
(-3550 5275);
DISPLAY 0.680851 (-3550 5275);
PAINT MONO (-3550 5275);
DISPLAY INVISIBLE (-3550 5275);
FORCEPROP 0 LAST CDS_SEC 1
J 0
(-3550 5275);
DISPLAY 1.021277 (-3550 5275);
DISPLAY INVISIBLE (-3550 5275);
FORCEPROP 1 LASTPIN (-3600 5225) $PN 1
J 0
(-3590 5205);
DISPLAY 0.489362 (-3590 5205);
PAINT MONO (-3590 5205);
FORCEPROP 1 LASTPIN (-3600 5025) $PN 2
J 0
(-3590 5005);
DISPLAY 0.489362 (-3590 5005);
PAINT MONO (-3590 5005);
FORCEPROP 1 LAST MATERIAL X7R
J 0
(-3550 5050);
DISPLAY 0.489362 (-3550 5050);
PAINT SKYBLUE (-3550 5050);
FORCEPROP 1 LAST TOLERANCE 10%
J 0
(-3550 5100);
DISPLAY 0.489362 (-3550 5100);
PAINT SKYBLUE (-3550 5100);
FORCEPROP 1 LAST VALUE 0.22UF
J 0
(-3550 5200);
DISPLAY 0.489362 (-3550 5200);
PAINT SKYBLUE (-3550 5200);
FORCEPROP 1 LAST PART_NUMBER CH4223K1B00
J 0
(-3550 5000);
DISPLAY 0.489362 (-3550 5000);
PAINT SKYBLUE (-3550 5000);
FORCEPROP 1 LAST VOLTAGE 16V
J 0
(-3550 5150);
DISPLAY 0.489362 (-3550 5150);
PAINT SKYBLUE (-3550 5150);
FORCEPROP 1 LAST PACK_TYPE 0402
J 0
(-3550 4950);
DISPLAY 0.489362 (-3550 4950);
PAINT SKYBLUE (-3550 4950);
FORCEPROP 2 LAST CDS_LIB pure_quanta
J 0
(-3600 5125);
DISPLAY INVISIBLE (-3600 5125);
FORCEPROP 1 LAST PATH I26
J 0
(-3550 5275);
DISPLAY 0.978723 (-3550 5275);
PAINT WHITE (-3550 5275);
DISPLAY INVISIBLE (-3550 5275);
FORCEADD UNIVERSAL_GND..1
(-4025 5475);
FORCEPROP 3 LASTPIN (-4025 5525) SIG_NAME GND\g
J 0
(-4015 5535);
DISPLAY 0.659574 (-4015 5535);
PAINT MONO (-4015 5535);
DISPLAY INVISIBLE (-4015 5535);
FORCEPROP 2 LAST CDS_LIB pure_quanta_power
J 0
(-4025 5475);
DISPLAY INVISIBLE (-4025 5475);
FORCEPROP 1 LAST PATH I27
J 0
(-3950 5475);
DISPLAY 0.872340 (-3950 5475);
PAINT AQUA (-3950 5475);
DISPLAY INVISIBLE (-3950 5475);
FORCEPROP 1 LAST HDL_POWER GND
J 1
(-4000 5400);
DISPLAY 0.872340 (-4000 5400);
PAINT GREEN (-4000 5400);
DISPLAY INVISIBLE (-4000 5400);
FORCEADD Q_CAP..1
(-4025 5800);
FORCEPROP 1 LAST LOCATION PC298_3
J 0
(-3975 5900);
DISPLAY 0.489362 (-3975 5900);
PAINT SKYBLUE (-3975 5900);
FORCEPROP 0 LAST $SEC 1
J 0
(-3975 5925);
DISPLAY 0.680851 (-3975 5925);
PAINT MONO (-3975 5925);
DISPLAY INVISIBLE (-3975 5925);
FORCEPROP 0 LAST CDS_SEC 1
J 0
(-3975 5925);
DISPLAY 1.021277 (-3975 5925);
DISPLAY INVISIBLE (-3975 5925);
FORCEPROP 1 LASTPIN (-4025 5900) $PN 1
J 0
(-4015 5880);
DISPLAY 0.489362 (-4015 5880);
PAINT MONO (-4015 5880);
FORCEPROP 1 LASTPIN (-4025 5700) $PN 2
J 0
(-4015 5680);
DISPLAY 0.489362 (-4015 5680);
PAINT MONO (-4015 5680);
FORCEPROP 1 LAST MATERIAL X6S
J 0
(-3975 5700);
DISPLAY 0.489362 (-3975 5700);
PAINT SKYBLUE (-3975 5700);
FORCEPROP 1 LAST TOLERANCE 10%
J 0
(-3975 5750);
DISPLAY 0.489362 (-3975 5750);
PAINT SKYBLUE (-3975 5750);
FORCEPROP 1 LAST VALUE 10UF
J 0
(-3975 5850);
DISPLAY 0.489362 (-3975 5850);
PAINT SKYBLUE (-3975 5850);
FORCEPROP 1 LAST PART_NUMBER CH6104KEA00
J 0
(-3975 5650);
DISPLAY 0.489362 (-3975 5650);
PAINT SKYBLUE (-3975 5650);
FORCEPROP 1 LAST VOLTAGE 25V
J 0
(-3975 5800);
DISPLAY 0.489362 (-3975 5800);
PAINT SKYBLUE (-3975 5800);
FORCEPROP 1 LAST PACK_TYPE C0805
J 0
(-3975 5600);
DISPLAY 0.489362 (-3975 5600);
PAINT SKYBLUE (-3975 5600);
FORCEPROP 2 LAST CDS_LIB pure_quanta
J 0
(-4025 5800);
DISPLAY INVISIBLE (-4025 5800);
FORCEPROP 1 LAST PATH I28
J 0
(-3975 5950);
DISPLAY 0.978723 (-3975 5950);
PAINT WHITE (-3975 5950);
DISPLAY INVISIBLE (-3975 5950);
FORCEADD VCC_CORE..1
(-4025 6100);
FORCEPROP 3 LASTPIN (-4025 6050) SIG_NAME SW_P12V_STBY_PVDDCR_CPU0_P1_FLT\g
J 0
(-4015 6060);
DISPLAY 0.659574 (-4015 6060);
PAINT MONO (-4015 6060);
DISPLAY INVISIBLE (-4015 6060);
FORCEPROP 1 LAST HDL_POWER SW_P12V_STBY_PVDDCR_CPU0_P1_FLT
J 1
(-4025 6150);
DISPLAY 0.489362 (-4025 6150);
PAINT GREEN (-4025 6150);
FORCEPROP 2 LAST CDS_LIB pure_quanta_power
J 0
(-4025 6100);
DISPLAY INVISIBLE (-4025 6100);
FORCEPROP 1 LAST PATH I29
J 0
(-3975 6125);
DISPLAY 0.872340 (-3975 6125);
PAINT AQUA (-3975 6125);
DISPLAY INVISIBLE (-3975 6125);
FORCEADD Q_CAP..1
(-7775 4625);
FORCEPROP 1 LAST LOCATION PC284_3
J 0
(-7725 4725);
DISPLAY 0.489362 (-7725 4725);
PAINT SKYBLUE (-7725 4725);
FORCEPROP 0 LAST $SEC 1
J 0
(-7725 4750);
DISPLAY 0.680851 (-7725 4750);
PAINT MONO (-7725 4750);
DISPLAY INVISIBLE (-7725 4750);
FORCEPROP 0 LAST CDS_SEC 1
J 0
(-7725 4750);
DISPLAY 1.021277 (-7725 4750);
DISPLAY INVISIBLE (-7725 4750);
FORCEPROP 1 LASTPIN (-7775 4725) $PN 1
J 0
(-7765 4705);
DISPLAY 0.489362 (-7765 4705);
PAINT MONO (-7765 4705);
FORCEPROP 1 LASTPIN (-7775 4525) $PN 2
J 0
(-7765 4505);
DISPLAY 0.489362 (-7765 4505);
PAINT MONO (-7765 4505);
FORCEPROP 1 LAST MATERIAL X7R
J 0
(-7725 4525);
DISPLAY 0.489362 (-7725 4525);
PAINT SKYBLUE (-7725 4525);
FORCEPROP 1 LAST TOLERANCE 10%
J 0
(-7725 4575);
DISPLAY 0.489362 (-7725 4575);
PAINT SKYBLUE (-7725 4575);
FORCEPROP 1 LAST VALUE 0.1UF
J 0
(-7725 4675);
DISPLAY 0.489362 (-7725 4675);
PAINT SKYBLUE (-7725 4675);
FORCEPROP 1 LAST PART_NUMBER CH4104K1B00
J 0
(-7725 4475);
DISPLAY 0.489362 (-7725 4475);
PAINT SKYBLUE (-7725 4475);
FORCEPROP 1 LAST VOLTAGE 25V
J 0
(-7725 4625);
DISPLAY 0.489362 (-7725 4625);
PAINT SKYBLUE (-7725 4625);
FORCEPROP 1 LAST PACK_TYPE 0402
J 0
(-7725 4425);
DISPLAY 0.489362 (-7725 4425);
PAINT SKYBLUE (-7725 4425);
FORCEPROP 2 LAST CDS_LIB pure_quanta
J 0
(-7775 4625);
DISPLAY INVISIBLE (-7775 4625);
FORCEPROP 1 LAST PATH I3
J 0
(-7725 4775);
DISPLAY 0.978723 (-7725 4775);
PAINT WHITE (-7725 4775);
DISPLAY INVISIBLE (-7725 4775);
FORCEADD Q_CAP..1
(-1250 4725);
FORCEPROP 1 LAST LOCATION PC302_3
J 0
(-1200 4825);
DISPLAY 0.489362 (-1200 4825);
PAINT SKYBLUE (-1200 4825);
FORCEPROP 0 LAST $SEC 1
J 0
(-1200 4850);
DISPLAY 0.680851 (-1200 4850);
PAINT MONO (-1200 4850);
DISPLAY INVISIBLE (-1200 4850);
FORCEPROP 0 LAST CDS_SEC 1
J 0
(-1200 4850);
DISPLAY 1.021277 (-1200 4850);
DISPLAY INVISIBLE (-1200 4850);
FORCEPROP 1 LASTPIN (-1250 4825) $PN 1
J 0
(-1240 4805);
DISPLAY 0.489362 (-1240 4805);
PAINT MONO (-1240 4805);
FORCEPROP 1 LASTPIN (-1250 4625) $PN 2
J 0
(-1240 4605);
DISPLAY 0.489362 (-1240 4605);
PAINT MONO (-1240 4605);
FORCEPROP 1 LAST MATERIAL X6S
J 0
(-1200 4625);
DISPLAY 0.489362 (-1200 4625);
PAINT SKYBLUE (-1200 4625);
FORCEPROP 1 LAST TOLERANCE 20%
J 0
(-1200 4675);
DISPLAY 0.489362 (-1200 4675);
PAINT SKYBLUE (-1200 4675);
FORCEPROP 1 LAST VALUE 22UF
J 0
(-1200 4775);
DISPLAY 0.489362 (-1200 4775);
PAINT SKYBLUE (-1200 4775);
FORCEPROP 1 LAST PART_NUMBER TMP_QCH622KMEA01
J 0
(-1200 4575);
DISPLAY 0.489362 (-1200 4575);
PAINT SKYBLUE (-1200 4575);
FORCEPROP 1 LAST VOLTAGE 4V
J 0
(-1200 4725);
DISPLAY 0.489362 (-1200 4725);
PAINT SKYBLUE (-1200 4725);
FORCEPROP 1 LAST PACK_TYPE 0805
J 0
(-1200 4525);
DISPLAY 0.489362 (-1200 4525);
PAINT SKYBLUE (-1200 4525);
FORCEPROP 2 LAST CDS_LIB pure_quanta
J 0
(-1250 4725);
DISPLAY INVISIBLE (-1250 4725);
FORCEPROP 1 LAST PATH I31
J 0
(-1200 4875);
DISPLAY 0.978723 (-1200 4875);
PAINT WHITE (-1200 4875);
DISPLAY INVISIBLE (-1200 4875);
FORCEADD UNIVERSAL_GND..1
(-825 4375);
FORCEPROP 3 LASTPIN (-825 4425) SIG_NAME GND\g
J 0
(-815 4435);
DISPLAY 0.659574 (-815 4435);
PAINT MONO (-815 4435);
DISPLAY INVISIBLE (-815 4435);
FORCEPROP 2 LAST CDS_LIB pure_quanta_power
J 0
(-825 4375);
DISPLAY INVISIBLE (-825 4375);
FORCEPROP 1 LAST PATH I32
J 0
(-750 4375);
DISPLAY 0.872340 (-750 4375);
PAINT AQUA (-750 4375);
DISPLAY INVISIBLE (-750 4375);
FORCEPROP 1 LAST HDL_POWER GND
J 1
(-800 4300);
DISPLAY 0.872340 (-800 4300);
PAINT GREEN (-800 4300);
DISPLAY INVISIBLE (-800 4300);
FORCEADD Q_CAP..1
(-825 4725);
FORCEPROP 1 LAST LOCATION PC304_3
J 0
(-775 4825);
DISPLAY 0.489362 (-775 4825);
PAINT SKYBLUE (-775 4825);
FORCEPROP 0 LAST $SEC 1
J 0
(-775 4850);
DISPLAY 0.680851 (-775 4850);
PAINT MONO (-775 4850);
DISPLAY INVISIBLE (-775 4850);
FORCEPROP 0 LAST CDS_SEC 1
J 0
(-775 4850);
DISPLAY 1.021277 (-775 4850);
DISPLAY INVISIBLE (-775 4850);
FORCEPROP 1 LASTPIN (-825 4825) $PN 1
J 0
(-815 4805);
DISPLAY 0.489362 (-815 4805);
PAINT MONO (-815 4805);
FORCEPROP 1 LASTPIN (-825 4625) $PN 2
J 0
(-815 4605);
DISPLAY 0.489362 (-815 4605);
PAINT MONO (-815 4605);
FORCEPROP 1 LAST MATERIAL X6S
J 0
(-775 4625);
DISPLAY 0.489362 (-775 4625);
PAINT SKYBLUE (-775 4625);
FORCEPROP 1 LAST TOLERANCE 20%
J 0
(-775 4675);
DISPLAY 0.489362 (-775 4675);
PAINT SKYBLUE (-775 4675);
FORCEPROP 1 LAST VALUE 22UF
J 0
(-775 4775);
DISPLAY 0.489362 (-775 4775);
PAINT SKYBLUE (-775 4775);
FORCEPROP 1 LAST PART_NUMBER TMP_QCH622KMEA01
J 0
(-775 4575);
DISPLAY 0.489362 (-775 4575);
PAINT SKYBLUE (-775 4575);
FORCEPROP 1 LAST VOLTAGE 4V
J 0
(-775 4725);
DISPLAY 0.489362 (-775 4725);
PAINT SKYBLUE (-775 4725);
FORCEPROP 1 LAST PACK_TYPE 0805
J 0
(-775 4525);
DISPLAY 0.489362 (-775 4525);
PAINT SKYBLUE (-775 4525);
FORCEPROP 2 LAST CDS_LIB pure_quanta
J 0
(-825 4725);
DISPLAY INVISIBLE (-825 4725);
FORCEPROP 1 LAST PATH I33
J 0
(-775 4875);
DISPLAY 0.978723 (-775 4875);
PAINT WHITE (-775 4875);
DISPLAY INVISIBLE (-775 4875);
FORCEADD VCC_CORE..1
(-825 5050);
FORCEPROP 3 LASTPIN (-825 5000) SIG_NAME PVDDCR_CPU0_P1\g
J 0
(-815 5010);
DISPLAY 0.659574 (-815 5010);
PAINT MONO (-815 5010);
DISPLAY INVISIBLE (-815 5010);
FORCEPROP 1 LAST HDL_POWER PVDDCR_CPU0_P1
J 1
(-825 5100);
DISPLAY 0.489362 (-825 5100);
PAINT GREEN (-825 5100);
FORCEPROP 2 LAST CDS_LIB pure_quanta_power
J 0
(-825 5050);
DISPLAY INVISIBLE (-825 5050);
FORCEPROP 1 LAST PATH I34
J 0
(-775 5075);
DISPLAY 0.872340 (-775 5075);
PAINT AQUA (-775 5075);
DISPLAY INVISIBLE (-775 5075);
FORCEADD ISL99390FRZTR5935..1
(-5950 4900);
FORCEPROP 1 LAST LOCATION PU27
J 0
(-6250 5775);
DISPLAY 0.489362 (-6250 5775);
PAINT SKYBLUE (-6250 5775);
FORCEPROP 0 LAST $SEC 1
J 0
(-6250 5925);
DISPLAY 0.680851 (-6250 5925);
PAINT MONO (-6250 5925);
DISPLAY INVISIBLE (-6250 5925);
FORCEPROP 2 LAST CDS_SEC 1
J 0
(-6250 5925);
DISPLAY 1.021277 (-6250 5925);
DISPLAY INVISIBLE (-6250 5925);
FORCEPROP 0 LASTPIN (-5550 4450) $PN 2
J 0
(-5540 4460);
DISPLAY 0.489362 (-5540 4460);
PAINT MONO (-5540 4460);
FORCEPROP 0 LASTPIN (-5550 5250) $PN 33
J 0
(-5540 5260);
DISPLAY 0.489362 (-5540 5260);
PAINT MONO (-5540 5260);
FORCEPROP 0 LASTPIN (-6400 4650) $PN 31
J 2
(-6410 4660);
DISPLAY 0.489362 (-6410 4660);
PAINT MONO (-6410 4660);
FORCEPROP 0 LASTPIN (-6400 5050) $PN 35
J 2
(-6410 5060);
DISPLAY 0.489362 (-6410 5060);
PAINT MONO (-6410 5060);
FORCEPROP 0 LASTPIN (-5550 4600) $PN 6
J 0
(-5540 4610);
DISPLAY 0.489362 (-5540 4610);
PAINT MONO (-5540 4610);
FORCEPROP 0 LASTPIN (-5550 4550) $PN 41
J 0
(-5540 4560);
DISPLAY 0.489362 (-5540 4560);
PAINT MONO (-5540 4560);
FORCEPROP 0 LASTPIN (-6400 4900) $PN 38
J 2
(-6410 4910);
DISPLAY 0.489362 (-6410 4910);
PAINT MONO (-6410 4910);
FORCEPROP 0 LASTPIN (-6400 4600) $PN 37
J 2
(-6410 4610);
DISPLAY 0.489362 (-6410 4610);
PAINT MONO (-6410 4610);
FORCEPROP 0 LASTPIN (-5550 4400) $PN 5
J 0
(-5540 4410);
DISPLAY 0.489362 (-5540 4410);
PAINT MONO (-5540 4410);
FORCEPROP 0 LASTPIN (-5550 4350) $PN 7_9-20_24
J 0
(-5540 4360);
DISPLAY 0.489362 (-5540 4360);
PAINT MONO (-5540 4360);
FORCEPROP 0 LASTPIN (-5550 4300) $PN 40
J 0
(-5540 4310);
DISPLAY 0.489362 (-5540 4310);
PAINT MONO (-5540 4310);
FORCEPROP 0 LASTPIN (-5550 5000) $PN 32
J 0
(-5540 5010);
DISPLAY 0.489362 (-5540 5010);
PAINT MONO (-5540 5010);
FORCEPROP 0 LASTPIN (-6400 5550) $PN 4
J 2
(-6410 5560);
DISPLAY 0.489362 (-6410 5560);
PAINT MONO (-6410 5560);
FORCEPROP 0 LASTPIN (-6400 4300) $PN 34
J 2
(-6410 4310);
DISPLAY 0.489362 (-6410 4310);
PAINT MONO (-6410 4310);
FORCEPROP 0 LASTPIN (-6400 4800) $PN 39
J 2
(-6410 4810);
DISPLAY 0.489362 (-6410 4810);
PAINT MONO (-6410 4810);
FORCEPROP 0 LASTPIN (-5550 4900) $PN 10_19
J 0
(-5540 4910);
DISPLAY 0.489362 (-5540 4910);
PAINT MONO (-5540 4910);
FORCEPROP 0 LASTPIN (-6400 4400) $PN 36
J 2
(-6410 4410);
DISPLAY 0.489362 (-6410 4410);
PAINT MONO (-6410 4410);
FORCEPROP 0 LASTPIN (-6400 5250) $PN 3
J 2
(-6410 5260);
DISPLAY 0.489362 (-6410 5260);
PAINT MONO (-6410 5260);
FORCEPROP 0 LASTPIN (-5550 5550) $PN 25_29
J 0
(-5540 5560);
DISPLAY 0.489362 (-5540 5560);
PAINT MONO (-5540 5560);
FORCEPROP 0 LASTPIN (-5550 5500) $PN 30
J 0
(-5540 5510);
DISPLAY 0.489362 (-5540 5510);
PAINT MONO (-5540 5510);
FORCEPROP 0 LASTPIN (-5550 4650) $PN 1
J 0
(-5540 4660);
DISPLAY 0.489362 (-5540 4660);
PAINT MONO (-5540 4660);
FORCEPROP 2 LAST PART_TYPE SMLF
J 0
(-6250 5875);
DISPLAY 1.021277 (-6250 5875);
FORCEPROP 1 LAST MATERIAL IC
J 0
(-6250 5625);
DISPLAY 0.489362 (-6250 5625);
PAINT SKYBLUE (-6250 5625);
FORCEPROP 2 LAST VALUE ISL99390FRZ-TR5935
J 0
(-6250 5825);
DISPLAY 0.489362 (-6250 5825);
PAINT SKYBLUE (-6250 5825);
FORCEPROP 1 LAST PART_NUMBER AL099390004
J 0
(-6250 5700);
DISPLAY 0.489362 (-6250 5700);
PAINT SKYBLUE (-6250 5700);
FORCEPROP 2 LAST CDS_LIB pure_quanta
J 0
(-5950 4900);
DISPLAY INVISIBLE (-5950 4900);
FORCEPROP 1 LAST NEEDS_NO_SIZE TRUE
J 0
(-5950 4900);
DISPLAY 0.723404 (-5950 4900);
PAINT GREEN (-5950 4900);
DISPLAY INVISIBLE (-5950 4900);
FORCEPROP 1 LAST CDS_LMAN_SYM_OUTLINE -300,700,250,-650
J 0
(-5950 4900);
DISPLAY 0.468085 (-5950 4900);
PAINT GREEN (-5950 4900);
DISPLAY INVISIBLE (-5950 4900);
FORCEPROP 1 LAST PATH I35
J 0
(-5950 4900);
DISPLAY 0.723404 (-5950 4900);
PAINT GREEN (-5950 4900);
DISPLAY INVISIBLE (-5950 4900);
FORCEADD UNIVERSAL_GND..1
(-7475 4425);
FORCEPROP 3 LASTPIN (-7475 4475) SIG_NAME GND\g
J 0
(-7465 4485);
DISPLAY 0.659574 (-7465 4485);
PAINT MONO (-7465 4485);
DISPLAY INVISIBLE (-7465 4485);
FORCEPROP 2 LAST CDS_LIB pure_quanta_power
J 0
(-7475 4425);
DISPLAY INVISIBLE (-7475 4425);
FORCEPROP 1 LAST PATH I4
J 0
(-7400 4425);
DISPLAY 0.872340 (-7400 4425);
PAINT AQUA (-7400 4425);
DISPLAY INVISIBLE (-7400 4425);
FORCEPROP 1 LAST HDL_POWER GND
J 1
(-7450 4350);
DISPLAY 0.872340 (-7450 4350);
PAINT GREEN (-7450 4350);
DISPLAY INVISIBLE (-7450 4350);
FORCEADD OFFPAGE..2
R 2
(-7100 4900);
FORCEPROP 2 LAST $XR0 186 
J 0
(-7355 4900);
DISPLAY 0.638298 (-7355 4900);
PAINT MONO (-7355 4900);
FORCEPROP 2 LAST PATH I5
J 0
(-7050 4975);
DISPLAY 1.021277 (-7050 4975);
DISPLAY INVISIBLE (-7050 4975);
FORCEPROP 1 LAST COMMENT_BODY TRUE
J 2
(-7055 4805);
DISPLAY 0.872340 (-7055 4805);
PAINT GREEN (-7055 4805);
DISPLAY INVISIBLE (-7055 4805);
FORCEPROP 1 LAST OFFPAGE TRUE
J 2
(-7425 4775);
DISPLAY 0.872340 (-7425 4775);
PAINT GREEN (-7425 4775);
DISPLAY INVISIBLE (-7425 4775);
FORCEPROP 2 LAST CDS_LIB standard
J 2
(-7100 4900);
DISPLAY INVISIBLE (-7100 4900);
FORCEADD OFFPAGE..2
R 2
(-7075 4400);
FORCEPROP 2 LAST $XR3 186 
J 0
(-7600 4364);
DISPLAY 0.638298 (-7600 4364);
PAINT MONO (-7600 4364);
FORCEPROP 2 LAST $XR2 189 
J 0
(-7480 4364);
DISPLAY 0.638298 (-7480 4364);
PAINT MONO (-7480 4364);
FORCEPROP 2 LAST $XR1 188 
J 0
(-7360 4364);
DISPLAY 0.638298 (-7360 4364);
PAINT MONO (-7360 4364);
FORCEPROP 2 LAST $XR0 187 
J 0
(-7360 4400);
DISPLAY 0.638298 (-7360 4400);
PAINT MONO (-7360 4400);
FORCEPROP 2 LAST PATH I6
J 0
(-7025 4475);
DISPLAY 1.021277 (-7025 4475);
DISPLAY INVISIBLE (-7025 4475);
FORCEPROP 1 LAST COMMENT_BODY TRUE
J 2
(-7030 4305);
DISPLAY 0.872340 (-7030 4305);
PAINT GREEN (-7030 4305);
DISPLAY INVISIBLE (-7030 4305);
FORCEPROP 1 LAST OFFPAGE TRUE
J 2
(-7400 4275);
DISPLAY 0.872340 (-7400 4275);
PAINT GREEN (-7400 4275);
DISPLAY INVISIBLE (-7400 4275);
FORCEPROP 2 LAST CDS_LIB standard
J 0
(-7075 4400);
DISPLAY INVISIBLE (-7075 4400);
FORCEADD OFFPAGE..1
(-7050 4300);
FORCEPROP 2 LAST $XR0 186 
J 0
(-7302 4300);
DISPLAY 0.638298 (-7302 4300);
PAINT MONO (-7302 4300);
FORCEPROP 2 LAST PATH I7
J 0
(-7000 4375);
DISPLAY 1.021277 (-7000 4375);
DISPLAY INVISIBLE (-7000 4375);
FORCEPROP 1 LAST COMMENT_BODY TRUE
J 0
(-6925 4200);
DISPLAY 0.872340 (-6925 4200);
PAINT GREEN (-6925 4200);
DISPLAY INVISIBLE (-6925 4200);
FORCEPROP 1 LAST OFFPAGE TRUE
J 0
(-6725 4175);
DISPLAY 0.872340 (-6725 4175);
PAINT GREEN (-6725 4175);
DISPLAY INVISIBLE (-6725 4175);
FORCEPROP 2 LAST CDS_LIB standard
J 2
(-7050 4300);
DISPLAY INVISIBLE (-7050 4300);
FORCEADD OFFPAGE..3
(-1675 4650);
FORCEPROP 2 LAST $XR0 188 
J 0
(-1371 4650);
DISPLAY 0.638298 (-1371 4650);
PAINT MONO (-1371 4650);
FORCEPROP 2 LAST PATH I71
J 2
(-1725 4725);
DISPLAY 1.021277 (-1725 4725);
DISPLAY INVISIBLE (-1725 4725);
FORCEPROP 1 LAST COMMENT_BODY TRUE
J 0
(-1725 4550);
DISPLAY 0.872340 (-1725 4550);
PAINT GREEN (-1725 4550);
DISPLAY INVISIBLE (-1725 4550);
FORCEPROP 1 LAST OFFPAGE TRUE
J 0
(-1350 4525);
DISPLAY 0.872340 (-1350 4525);
PAINT GREEN (-1350 4525);
DISPLAY INVISIBLE (-1350 4525);
FORCEPROP 2 LAST CDS_LIB standard
J 2
(-1675 4650);
DISPLAY INVISIBLE (-1675 4650);
FORCEADD ISL99390FRZTR5935..1
(-5875 1600);
FORCEPROP 1 LAST LOCATION PU28
J 0
(-6175 2475);
DISPLAY 0.489362 (-6175 2475);
PAINT SKYBLUE (-6175 2475);
FORCEPROP 0 LAST $SEC 1
J 0
(-6175 2625);
DISPLAY 0.680851 (-6175 2625);
PAINT MONO (-6175 2625);
DISPLAY INVISIBLE (-6175 2625);
FORCEPROP 2 LAST CDS_SEC 1
J 0
(-6175 2625);
DISPLAY 1.021277 (-6175 2625);
DISPLAY INVISIBLE (-6175 2625);
FORCEPROP 0 LASTPIN (-5475 1150) $PN 2
J 0
(-5465 1160);
DISPLAY 0.489362 (-5465 1160);
PAINT MONO (-5465 1160);
FORCEPROP 0 LASTPIN (-5475 1950) $PN 33
J 0
(-5465 1960);
DISPLAY 0.489362 (-5465 1960);
PAINT MONO (-5465 1960);
FORCEPROP 0 LASTPIN (-6325 1350) $PN 31
J 2
(-6335 1360);
DISPLAY 0.489362 (-6335 1360);
PAINT MONO (-6335 1360);
FORCEPROP 0 LASTPIN (-6325 1750) $PN 35
J 2
(-6335 1760);
DISPLAY 0.489362 (-6335 1760);
PAINT MONO (-6335 1760);
FORCEPROP 0 LASTPIN (-5475 1300) $PN 6
J 0
(-5465 1310);
DISPLAY 0.489362 (-5465 1310);
PAINT MONO (-5465 1310);
FORCEPROP 0 LASTPIN (-5475 1250) $PN 41
J 0
(-5465 1260);
DISPLAY 0.489362 (-5465 1260);
PAINT MONO (-5465 1260);
FORCEPROP 0 LASTPIN (-6325 1600) $PN 38
J 2
(-6335 1610);
DISPLAY 0.489362 (-6335 1610);
PAINT MONO (-6335 1610);
FORCEPROP 0 LASTPIN (-6325 1300) $PN 37
J 2
(-6335 1310);
DISPLAY 0.489362 (-6335 1310);
PAINT MONO (-6335 1310);
FORCEPROP 0 LASTPIN (-5475 1100) $PN 5
J 0
(-5465 1110);
DISPLAY 0.489362 (-5465 1110);
PAINT MONO (-5465 1110);
FORCEPROP 0 LASTPIN (-5475 1050) $PN 7_9-20_24
J 0
(-5465 1060);
DISPLAY 0.489362 (-5465 1060);
PAINT MONO (-5465 1060);
FORCEPROP 0 LASTPIN (-5475 1000) $PN 40
J 0
(-5465 1010);
DISPLAY 0.489362 (-5465 1010);
PAINT MONO (-5465 1010);
FORCEPROP 0 LASTPIN (-5475 1700) $PN 32
J 0
(-5465 1710);
DISPLAY 0.489362 (-5465 1710);
PAINT MONO (-5465 1710);
FORCEPROP 0 LASTPIN (-6325 2250) $PN 4
J 2
(-6335 2260);
DISPLAY 0.489362 (-6335 2260);
PAINT MONO (-6335 2260);
FORCEPROP 0 LASTPIN (-6325 1000) $PN 34
J 2
(-6335 1010);
DISPLAY 0.489362 (-6335 1010);
PAINT MONO (-6335 1010);
FORCEPROP 0 LASTPIN (-6325 1500) $PN 39
J 2
(-6335 1510);
DISPLAY 0.489362 (-6335 1510);
PAINT MONO (-6335 1510);
FORCEPROP 0 LASTPIN (-5475 1600) $PN 10_19
J 0
(-5465 1610);
DISPLAY 0.489362 (-5465 1610);
PAINT MONO (-5465 1610);
FORCEPROP 0 LASTPIN (-6325 1100) $PN 36
J 2
(-6335 1110);
DISPLAY 0.489362 (-6335 1110);
PAINT MONO (-6335 1110);
FORCEPROP 0 LASTPIN (-6325 1950) $PN 3
J 2
(-6335 1960);
DISPLAY 0.489362 (-6335 1960);
PAINT MONO (-6335 1960);
FORCEPROP 0 LASTPIN (-5475 2250) $PN 25_29
J 0
(-5465 2260);
DISPLAY 0.489362 (-5465 2260);
PAINT MONO (-5465 2260);
FORCEPROP 0 LASTPIN (-5475 2200) $PN 30
J 0
(-5465 2210);
DISPLAY 0.489362 (-5465 2210);
PAINT MONO (-5465 2210);
FORCEPROP 0 LASTPIN (-5475 1350) $PN 1
J 0
(-5465 1360);
DISPLAY 0.489362 (-5465 1360);
PAINT MONO (-5465 1360);
FORCEPROP 2 LAST PART_TYPE SMLF
J 0
(-6175 2575);
DISPLAY 1.021277 (-6175 2575);
FORCEPROP 1 LAST MATERIAL IC
J 0
(-6175 2325);
DISPLAY 0.489362 (-6175 2325);
PAINT SKYBLUE (-6175 2325);
FORCEPROP 2 LAST VALUE ISL99390FRZ-TR5935
J 0
(-6175 2525);
DISPLAY 0.489362 (-6175 2525);
PAINT SKYBLUE (-6175 2525);
FORCEPROP 1 LAST PART_NUMBER AL099390004
J 0
(-6175 2400);
DISPLAY 0.489362 (-6175 2400);
PAINT SKYBLUE (-6175 2400);
FORCEPROP 2 LAST CDS_LIB pure_quanta
J 0
(-5875 1600);
DISPLAY INVISIBLE (-5875 1600);
FORCEPROP 1 LAST CDS_LMAN_SYM_OUTLINE -300,700,250,-650
J 0
(-5875 1600);
DISPLAY 0.468085 (-5875 1600);
PAINT GREEN (-5875 1600);
DISPLAY INVISIBLE (-5875 1600);
FORCEPROP 1 LAST NEEDS_NO_SIZE TRUE
J 0
(-5875 1600);
DISPLAY 0.723404 (-5875 1600);
PAINT GREEN (-5875 1600);
DISPLAY INVISIBLE (-5875 1600);
FORCEPROP 1 LAST PATH I72
J 0
(-5875 1600);
DISPLAY 0.723404 (-5875 1600);
PAINT GREEN (-5875 1600);
DISPLAY INVISIBLE (-5875 1600);
FORCEADD OFFPAGE..3
R 2
(-3450 1350);
FORCEPROP 2 LAST $XR0 188 
J 0
(-3760 1350);
DISPLAY 0.638298 (-3760 1350);
PAINT MONO (-3760 1350);
FORCEPROP 2 LAST PATH I73
J 0
(-3400 1425);
DISPLAY 1.021277 (-3400 1425);
DISPLAY INVISIBLE (-3400 1425);
FORCEPROP 1 LAST COMMENT_BODY TRUE
J 2
(-3400 1250);
DISPLAY 0.872340 (-3400 1250);
PAINT GREEN (-3400 1250);
DISPLAY INVISIBLE (-3400 1250);
FORCEPROP 1 LAST OFFPAGE TRUE
J 2
(-3775 1225);
DISPLAY 0.872340 (-3775 1225);
PAINT GREEN (-3775 1225);
DISPLAY INVISIBLE (-3775 1225);
FORCEPROP 2 LAST CDS_LIB standard
J 2
(-3450 1350);
DISPLAY INVISIBLE (-3450 1350);
FORCEADD VCC_CORE..1
(-775 1750);
FORCEPROP 3 LASTPIN (-775 1700) SIG_NAME PVDDCR_CPU0_P1\g
J 0
(-765 1710);
DISPLAY 0.659574 (-765 1710);
PAINT MONO (-765 1710);
DISPLAY INVISIBLE (-765 1710);
FORCEPROP 1 LAST HDL_POWER PVDDCR_CPU0_P1
J 1
(-775 1800);
DISPLAY 0.489362 (-775 1800);
PAINT GREEN (-775 1800);
FORCEPROP 2 LAST CDS_LIB pure_quanta_power
J 0
(-775 1750);
DISPLAY INVISIBLE (-775 1750);
FORCEPROP 1 LAST PATH I74
J 0
(-725 1775);
DISPLAY 0.872340 (-725 1775);
PAINT AQUA (-725 1775);
DISPLAY INVISIBLE (-725 1775);
FORCEADD Q_CAP..1
(-775 1425);
FORCEPROP 1 LAST LOCATION PC305_4
J 0
(-725 1525);
DISPLAY 0.489362 (-725 1525);
PAINT SKYBLUE (-725 1525);
FORCEPROP 0 LAST $SEC 1
J 0
(-725 1550);
DISPLAY 0.680851 (-725 1550);
PAINT MONO (-725 1550);
DISPLAY INVISIBLE (-725 1550);
FORCEPROP 0 LAST CDS_SEC 1
J 0
(-725 1550);
DISPLAY 1.021277 (-725 1550);
DISPLAY INVISIBLE (-725 1550);
FORCEPROP 1 LASTPIN (-775 1525) $PN 1
J 0
(-765 1505);
DISPLAY 0.489362 (-765 1505);
PAINT MONO (-765 1505);
FORCEPROP 1 LASTPIN (-775 1325) $PN 2
J 0
(-765 1305);
DISPLAY 0.489362 (-765 1305);
PAINT MONO (-765 1305);
FORCEPROP 1 LAST MATERIAL X6S
J 0
(-725 1325);
DISPLAY 0.489362 (-725 1325);
PAINT SKYBLUE (-725 1325);
FORCEPROP 1 LAST TOLERANCE 20%
J 0
(-725 1375);
DISPLAY 0.489362 (-725 1375);
PAINT SKYBLUE (-725 1375);
FORCEPROP 1 LAST VALUE 22UF
J 0
(-725 1475);
DISPLAY 0.489362 (-725 1475);
PAINT SKYBLUE (-725 1475);
FORCEPROP 1 LAST PART_NUMBER TMP_QCH622KMEA01
J 0
(-725 1275);
DISPLAY 0.489362 (-725 1275);
PAINT SKYBLUE (-725 1275);
FORCEPROP 1 LAST VOLTAGE 4V
J 0
(-725 1425);
DISPLAY 0.489362 (-725 1425);
PAINT SKYBLUE (-725 1425);
FORCEPROP 1 LAST PACK_TYPE 0805
J 0
(-725 1225);
DISPLAY 0.489362 (-725 1225);
PAINT SKYBLUE (-725 1225);
FORCEPROP 2 LAST CDS_LIB pure_quanta
J 0
(-775 1425);
DISPLAY INVISIBLE (-775 1425);
FORCEPROP 1 LAST PATH I75
J 0
(-725 1575);
DISPLAY 0.978723 (-725 1575);
PAINT WHITE (-725 1575);
DISPLAY INVISIBLE (-725 1575);
FORCEADD UNIVERSAL_GND..1
(-775 1075);
FORCEPROP 3 LASTPIN (-775 1125) SIG_NAME GND\g
J 0
(-765 1135);
DISPLAY 0.659574 (-765 1135);
PAINT MONO (-765 1135);
DISPLAY INVISIBLE (-765 1135);
FORCEPROP 2 LAST CDS_LIB pure_quanta_power
J 0
(-775 1075);
DISPLAY INVISIBLE (-775 1075);
FORCEPROP 1 LAST PATH I76
J 0
(-700 1075);
DISPLAY 0.872340 (-700 1075);
PAINT AQUA (-700 1075);
DISPLAY INVISIBLE (-700 1075);
FORCEPROP 1 LAST HDL_POWER GND
J 1
(-750 1000);
DISPLAY 0.872340 (-750 1000);
PAINT GREEN (-750 1000);
DISPLAY INVISIBLE (-750 1000);
FORCEADD Q_CAP..1
(-1200 1425);
FORCEPROP 1 LAST LOCATION PC303_4
J 0
(-1150 1525);
DISPLAY 0.489362 (-1150 1525);
PAINT SKYBLUE (-1150 1525);
FORCEPROP 0 LAST $SEC 1
J 0
(-1150 1550);
DISPLAY 0.680851 (-1150 1550);
PAINT MONO (-1150 1550);
DISPLAY INVISIBLE (-1150 1550);
FORCEPROP 0 LAST CDS_SEC 1
J 0
(-1150 1550);
DISPLAY 1.021277 (-1150 1550);
DISPLAY INVISIBLE (-1150 1550);
FORCEPROP 1 LASTPIN (-1200 1525) $PN 1
J 0
(-1190 1505);
DISPLAY 0.489362 (-1190 1505);
PAINT MONO (-1190 1505);
FORCEPROP 1 LASTPIN (-1200 1325) $PN 2
J 0
(-1190 1305);
DISPLAY 0.489362 (-1190 1305);
PAINT MONO (-1190 1305);
FORCEPROP 1 LAST MATERIAL X6S
J 0
(-1150 1325);
DISPLAY 0.489362 (-1150 1325);
PAINT SKYBLUE (-1150 1325);
FORCEPROP 1 LAST TOLERANCE 20%
J 0
(-1150 1375);
DISPLAY 0.489362 (-1150 1375);
PAINT SKYBLUE (-1150 1375);
FORCEPROP 1 LAST VALUE 22UF
J 0
(-1150 1475);
DISPLAY 0.489362 (-1150 1475);
PAINT SKYBLUE (-1150 1475);
FORCEPROP 1 LAST PART_NUMBER TMP_QCH622KMEA01
J 0
(-1150 1275);
DISPLAY 0.489362 (-1150 1275);
PAINT SKYBLUE (-1150 1275);
FORCEPROP 1 LAST VOLTAGE 4V
J 0
(-1150 1425);
DISPLAY 0.489362 (-1150 1425);
PAINT SKYBLUE (-1150 1425);
FORCEPROP 1 LAST PACK_TYPE 0805
J 0
(-1150 1225);
DISPLAY 0.489362 (-1150 1225);
PAINT SKYBLUE (-1150 1225);
FORCEPROP 2 LAST CDS_LIB pure_quanta
J 0
(-1200 1425);
DISPLAY INVISIBLE (-1200 1425);
FORCEPROP 1 LAST PATH I77
J 0
(-1150 1575);
DISPLAY 0.978723 (-1150 1575);
PAINT WHITE (-1150 1575);
DISPLAY INVISIBLE (-1150 1575);
FORCEADD Q_RES..1
(-7150 4600);
FORCEPROP 1 LAST LOCATION PR195
J 0
(-7200 4650);
DISPLAY 0.489362 (-7200 4650);
PAINT SKYBLUE (-7200 4650);
FORCEPROP 0 LAST $SEC 1
J 0
(-7150 4675);
DISPLAY 0.680851 (-7150 4675);
PAINT MONO (-7150 4675);
DISPLAY INVISIBLE (-7150 4675);
FORCEPROP 0 LAST CDS_SEC 1
J 0
(-7150 4675);
DISPLAY 1.021277 (-7150 4675);
DISPLAY INVISIBLE (-7150 4675);
FORCEPROP 1 LASTPIN (-7250 4600) $PN 1
J 0
(-7238 4612);
DISPLAY 0.489362 (-7238 4612);
PAINT MONO (-7238 4612);
FORCEPROP 1 LASTPIN (-7050 4600) $PN 2
J 0
(-7088 4612);
DISPLAY 0.489362 (-7088 4612);
PAINT MONO (-7088 4612);
FORCEPROP 1 LAST WATTAGE 1/16W
J 0
(-7050 4500);
DISPLAY 0.489362 (-7050 4500);
PAINT SKYBLUE (-7050 4500);
FORCEPROP 1 LAST MATERIAL EMPTY
J 0
(-7450 4500);
DISPLAY 0.489362 (-7450 4500);
PAINT RED (-7450 4500);
FORCEPROP 1 LAST TOLERANCE 1%
J 0
(-7025 4625);
DISPLAY 0.489362 (-7025 4625);
PAINT SKYBLUE (-7025 4625);
FORCEPROP 1 LAST VALUE 8.87K
J 2
(-7275 4625);
DISPLAY 0.489362 (-7275 4625);
PAINT SKYBLUE (-7275 4625);
FORCEPROP 1 LAST PART_NUMBER CS28872FB01
J 0
(-7450 4550);
DISPLAY 0.489362 (-7450 4550);
PAINT SKYBLUE (-7450 4550);
FORCEPROP 1 LAST PACK_TYPE 0402LF
J 0
(-7050 4550);
DISPLAY 0.489362 (-7050 4550);
PAINT SKYBLUE (-7050 4550);
FORCEPROP 2 LAST CDS_LIB pure_quanta
J 0
(-7150 4600);
DISPLAY INVISIBLE (-7150 4600);
FORCEPROP 1 LAST PATH I8
J 0
(-7200 4750);
DISPLAY 0.978723 (-7200 4750);
PAINT WHITE (-7200 4750);
DISPLAY INVISIBLE (-7200 4750);
FORCEADD VCC_CORE..1
(-3875 2800);
FORCEPROP 3 LASTPIN (-3875 2750) SIG_NAME SW_P12V_STBY_PVDDCR_CPU0_P1_FLT\g
J 0
(-3865 2760);
DISPLAY 0.659574 (-3865 2760);
PAINT MONO (-3865 2760);
DISPLAY INVISIBLE (-3865 2760);
FORCEPROP 1 LAST HDL_POWER SW_P12V_STBY_PVDDCR_CPU0_P1_FLT
J 1
(-3875 2850);
DISPLAY 0.489362 (-3875 2850);
PAINT GREEN (-3875 2850);
FORCEPROP 2 LAST CDS_LIB pure_quanta_power
J 0
(-3875 2800);
DISPLAY INVISIBLE (-3875 2800);
FORCEPROP 1 LAST PATH I81
J 0
(-3825 2825);
DISPLAY 0.872340 (-3825 2825);
PAINT AQUA (-3825 2825);
DISPLAY INVISIBLE (-3825 2825);
FORCEADD Q_CAP..1
(-3875 2500);
FORCEPROP 1 LAST LOCATION PC299_4
J 0
(-3825 2600);
DISPLAY 0.489362 (-3825 2600);
PAINT SKYBLUE (-3825 2600);
FORCEPROP 0 LAST $SEC 1
J 0
(-3825 2625);
DISPLAY 0.680851 (-3825 2625);
PAINT MONO (-3825 2625);
DISPLAY INVISIBLE (-3825 2625);
FORCEPROP 0 LAST CDS_SEC 1
J 0
(-3825 2625);
DISPLAY 1.021277 (-3825 2625);
DISPLAY INVISIBLE (-3825 2625);
FORCEPROP 1 LASTPIN (-3875 2600) $PN 1
J 0
(-3865 2580);
DISPLAY 0.489362 (-3865 2580);
PAINT MONO (-3865 2580);
FORCEPROP 1 LASTPIN (-3875 2400) $PN 2
J 0
(-3865 2380);
DISPLAY 0.489362 (-3865 2380);
PAINT MONO (-3865 2380);
FORCEPROP 1 LAST MATERIAL X6S
J 0
(-3825 2400);
DISPLAY 0.489362 (-3825 2400);
PAINT SKYBLUE (-3825 2400);
FORCEPROP 1 LAST TOLERANCE 10%
J 0
(-3825 2450);
DISPLAY 0.489362 (-3825 2450);
PAINT SKYBLUE (-3825 2450);
FORCEPROP 1 LAST VALUE 10UF
J 0
(-3825 2550);
DISPLAY 0.489362 (-3825 2550);
PAINT SKYBLUE (-3825 2550);
FORCEPROP 1 LAST PART_NUMBER CH6104KEA00
J 0
(-3825 2350);
DISPLAY 0.489362 (-3825 2350);
PAINT SKYBLUE (-3825 2350);
FORCEPROP 1 LAST VOLTAGE 25V
J 0
(-3825 2500);
DISPLAY 0.489362 (-3825 2500);
PAINT SKYBLUE (-3825 2500);
FORCEPROP 1 LAST PACK_TYPE C0805
J 0
(-3825 2300);
DISPLAY 0.489362 (-3825 2300);
PAINT SKYBLUE (-3825 2300);
FORCEPROP 2 LAST CDS_LIB pure_quanta
J 0
(-3875 2500);
DISPLAY INVISIBLE (-3875 2500);
FORCEPROP 1 LAST PATH I82
J 0
(-3825 2650);
DISPLAY 0.978723 (-3825 2650);
PAINT WHITE (-3825 2650);
DISPLAY INVISIBLE (-3825 2650);
FORCEADD UNIVERSAL_GND..1
(-3875 2150);
FORCEPROP 3 LASTPIN (-3875 2200) SIG_NAME GND\g
J 0
(-3865 2210);
DISPLAY 0.659574 (-3865 2210);
PAINT MONO (-3865 2210);
DISPLAY INVISIBLE (-3865 2210);
FORCEPROP 2 LAST CDS_LIB pure_quanta_power
J 0
(-3875 2150);
DISPLAY INVISIBLE (-3875 2150);
FORCEPROP 1 LAST PATH I83
J 0
(-3800 2150);
DISPLAY 0.872340 (-3800 2150);
PAINT AQUA (-3800 2150);
DISPLAY INVISIBLE (-3800 2150);
FORCEPROP 1 LAST HDL_POWER GND
J 1
(-3850 2075);
DISPLAY 0.872340 (-3850 2075);
PAINT GREEN (-3850 2075);
DISPLAY INVISIBLE (-3850 2075);
FORCEADD Q_INDUCTOR4P_14..1
(-2550 1475);
FORCEPROP 1 LAST LOCATION PL32
J 0
(-2775 1730);
DISPLAY 0.489362 (-2775 1730);
PAINT SKYBLUE (-2775 1730);
FORCEPROP 0 LAST $SEC 1
J 0
(-2775 1875);
DISPLAY 0.680851 (-2775 1875);
PAINT MONO (-2775 1875);
DISPLAY INVISIBLE (-2775 1875);
FORCEPROP 0 LAST CDS_SEC 1
J 0
(-2775 1875);
DISPLAY 1.021277 (-2775 1875);
DISPLAY INVISIBLE (-2775 1875);
FORCEPROP 0 LASTPIN (-2950 1600) $PN 1
J 2
(-2960 1610);
DISPLAY 0.489362 (-2960 1610);
PAINT MONO (-2960 1610);
FORCEPROP 0 LASTPIN (-2950 1350) $PN 2
J 2
(-2960 1360);
DISPLAY 0.489362 (-2960 1360);
PAINT MONO (-2960 1360);
FORCEPROP 0 LASTPIN (-2150 1350) $PN 3
J 0
(-2140 1360);
DISPLAY 0.489362 (-2140 1360);
PAINT MONO (-2140 1360);
FORCEPROP 0 LASTPIN (-2150 1600) $PN 4
J 0
(-2140 1610);
DISPLAY 0.489362 (-2140 1610);
PAINT MONO (-2140 1610);
FORCEPROP 2 LAST PART_TYPE SMLF
J 0
(-2775 1825);
DISPLAY 1.021277 (-2775 1825);
FORCEPROP 1 LAST MATERIAL IND
J 0
(-2775 1685);
DISPLAY 0.489362 (-2775 1685);
PAINT SKYBLUE (-2775 1685);
FORCEPROP 2 LAST VALUE 150NH
J 0
(-2775 1775);
DISPLAY 0.489362 (-2775 1775);
PAINT SKYBLUE (-2775 1775);
FORCEPROP 1 LAST PART_NUMBER CV+15^0TZ04
J 0
(-2775 1635);
DISPLAY 0.489362 (-2775 1635);
PAINT SKYBLUE (-2775 1635);
FORCEPROP 1 LAST NEEDS_NO_SIZE TRUE
J 0
(-2550 1475);
DISPLAY 0.468085 (-2550 1475);
PAINT GREEN (-2550 1475);
DISPLAY INVISIBLE (-2550 1475);
FORCEPROP 2 LAST CDS_LIB pure_quanta
J 0
(-2550 1475);
DISPLAY INVISIBLE (-2550 1475);
FORCEPROP 1 LAST PATH I84
J 0
(-2350 1630);
DISPLAY 0.723404 (-2350 1630);
PAINT GREEN (-2350 1630);
DISPLAY INVISIBLE (-2350 1630);
FORCEADD Q_CAP..1
(-3525 1825);
FORCEPROP 1 LAST LOCATION PC301
J 0
(-3475 1950);
DISPLAY 0.489362 (-3475 1950);
PAINT SKYBLUE (-3475 1950);
FORCEPROP 0 LAST $SEC 1
J 0
(-3475 1975);
DISPLAY 0.680851 (-3475 1975);
PAINT MONO (-3475 1975);
DISPLAY INVISIBLE (-3475 1975);
FORCEPROP 0 LAST CDS_SEC 1
J 0
(-3475 1975);
DISPLAY 1.021277 (-3475 1975);
DISPLAY INVISIBLE (-3475 1975);
FORCEPROP 1 LASTPIN (-3525 1925) $PN 1
J 0
(-3515 1905);
DISPLAY 0.489362 (-3515 1905);
PAINT MONO (-3515 1905);
FORCEPROP 1 LASTPIN (-3525 1725) $PN 2
J 0
(-3515 1705);
DISPLAY 0.489362 (-3515 1705);
PAINT MONO (-3515 1705);
FORCEPROP 1 LAST MATERIAL X7R
J 0
(-3475 1750);
DISPLAY 0.489362 (-3475 1750);
PAINT SKYBLUE (-3475 1750);
FORCEPROP 1 LAST TOLERANCE 10%
J 0
(-3475 1800);
DISPLAY 0.489362 (-3475 1800);
PAINT SKYBLUE (-3475 1800);
FORCEPROP 1 LAST VALUE 0.22UF
J 0
(-3475 1900);
DISPLAY 0.489362 (-3475 1900);
PAINT SKYBLUE (-3475 1900);
FORCEPROP 1 LAST PART_NUMBER CH4223K1B00
J 0
(-3475 1700);
DISPLAY 0.489362 (-3475 1700);
PAINT SKYBLUE (-3475 1700);
FORCEPROP 1 LAST VOLTAGE 16V
J 0
(-3475 1850);
DISPLAY 0.489362 (-3475 1850);
PAINT SKYBLUE (-3475 1850);
FORCEPROP 1 LAST PACK_TYPE 0402
J 0
(-3475 1650);
DISPLAY 0.489362 (-3475 1650);
PAINT SKYBLUE (-3475 1650);
FORCEPROP 2 LAST CDS_LIB pure_quanta
J 0
(-3525 1825);
DISPLAY INVISIBLE (-3525 1825);
FORCEPROP 1 LAST PATH I85
J 0
(-3475 1975);
DISPLAY 0.978723 (-3475 1975);
PAINT WHITE (-3475 1975);
DISPLAY INVISIBLE (-3475 1975);
FORCEADD Q_CAP..1
(-4175 2500);
FORCEPROP 1 LAST LOCATION PC297_4
J 0
(-4125 2600);
DISPLAY 0.489362 (-4125 2600);
PAINT SKYBLUE (-4125 2600);
FORCEPROP 0 LAST $SEC 1
J 0
(-4125 2625);
DISPLAY 0.680851 (-4125 2625);
PAINT MONO (-4125 2625);
DISPLAY INVISIBLE (-4125 2625);
FORCEPROP 0 LAST CDS_SEC 1
J 0
(-4125 2625);
DISPLAY 1.021277 (-4125 2625);
DISPLAY INVISIBLE (-4125 2625);
FORCEPROP 1 LASTPIN (-4175 2600) $PN 1
J 0
(-4165 2580);
DISPLAY 0.489362 (-4165 2580);
PAINT MONO (-4165 2580);
FORCEPROP 1 LASTPIN (-4175 2400) $PN 2
J 0
(-4165 2380);
DISPLAY 0.489362 (-4165 2380);
PAINT MONO (-4165 2380);
FORCEPROP 1 LAST MATERIAL X6S
J 0
(-4125 2400);
DISPLAY 0.489362 (-4125 2400);
PAINT SKYBLUE (-4125 2400);
FORCEPROP 1 LAST TOLERANCE 10%
J 0
(-4125 2450);
DISPLAY 0.489362 (-4125 2450);
PAINT SKYBLUE (-4125 2450);
FORCEPROP 1 LAST VALUE 10UF
J 0
(-4125 2550);
DISPLAY 0.489362 (-4125 2550);
PAINT SKYBLUE (-4125 2550);
FORCEPROP 1 LAST PART_NUMBER CH6104KEA00
J 0
(-4125 2350);
DISPLAY 0.489362 (-4125 2350);
PAINT SKYBLUE (-4125 2350);
FORCEPROP 1 LAST VOLTAGE 25V
J 0
(-4125 2500);
DISPLAY 0.489362 (-4125 2500);
PAINT SKYBLUE (-4125 2500);
FORCEPROP 1 LAST PACK_TYPE C0805
J 0
(-4125 2300);
DISPLAY 0.489362 (-4125 2300);
PAINT SKYBLUE (-4125 2300);
FORCEPROP 2 LAST CDS_LIB pure_quanta
J 0
(-4175 2500);
DISPLAY INVISIBLE (-4175 2500);
FORCEPROP 1 LAST PATH I86
J 0
(-4125 2650);
DISPLAY 0.978723 (-4125 2650);
PAINT WHITE (-4125 2650);
DISPLAY INVISIBLE (-4125 2650);
FORCEADD Q_CAP..1
(-4500 2500);
FORCEPROP 1 LAST LOCATION PC295_4
J 0
(-4450 2600);
DISPLAY 0.489362 (-4450 2600);
PAINT SKYBLUE (-4450 2600);
FORCEPROP 0 LAST $SEC 1
J 0
(-4450 2625);
DISPLAY 0.680851 (-4450 2625);
PAINT MONO (-4450 2625);
DISPLAY INVISIBLE (-4450 2625);
FORCEPROP 0 LAST CDS_SEC 1
J 0
(-4450 2625);
DISPLAY 1.021277 (-4450 2625);
DISPLAY INVISIBLE (-4450 2625);
FORCEPROP 1 LASTPIN (-4500 2600) $PN 1
J 0
(-4490 2580);
DISPLAY 0.489362 (-4490 2580);
PAINT MONO (-4490 2580);
FORCEPROP 1 LASTPIN (-4500 2400) $PN 2
J 0
(-4490 2380);
DISPLAY 0.489362 (-4490 2380);
PAINT MONO (-4490 2380);
FORCEPROP 1 LAST MATERIAL X6S
J 0
(-4450 2400);
DISPLAY 0.489362 (-4450 2400);
PAINT SKYBLUE (-4450 2400);
FORCEPROP 1 LAST TOLERANCE 10%
J 0
(-4450 2450);
DISPLAY 0.489362 (-4450 2450);
PAINT SKYBLUE (-4450 2450);
FORCEPROP 1 LAST VALUE 10UF
J 0
(-4450 2550);
DISPLAY 0.489362 (-4450 2550);
PAINT SKYBLUE (-4450 2550);
FORCEPROP 1 LAST PART_NUMBER CH6104KEA00
J 0
(-4450 2350);
DISPLAY 0.489362 (-4450 2350);
PAINT SKYBLUE (-4450 2350);
FORCEPROP 1 LAST VOLTAGE 25V
J 0
(-4450 2500);
DISPLAY 0.489362 (-4450 2500);
PAINT SKYBLUE (-4450 2500);
FORCEPROP 1 LAST PACK_TYPE C0805
J 0
(-4450 2300);
DISPLAY 0.489362 (-4450 2300);
PAINT SKYBLUE (-4450 2300);
FORCEPROP 2 LAST CDS_LIB pure_quanta
J 0
(-4500 2500);
DISPLAY INVISIBLE (-4500 2500);
FORCEPROP 1 LAST PATH I87
J 0
(-4450 2650);
DISPLAY 0.978723 (-4450 2650);
PAINT WHITE (-4450 2650);
DISPLAY INVISIBLE (-4450 2650);
FORCEADD Q_CAP..1
(-4825 2500);
FORCEPROP 1 LAST LOCATION PC293_4
J 0
(-4775 2600);
DISPLAY 0.489362 (-4775 2600);
PAINT SKYBLUE (-4775 2600);
FORCEPROP 0 LAST $SEC 1
J 0
(-4775 2625);
DISPLAY 0.680851 (-4775 2625);
PAINT MONO (-4775 2625);
DISPLAY INVISIBLE (-4775 2625);
FORCEPROP 0 LAST CDS_SEC 1
J 0
(-4775 2625);
DISPLAY 1.021277 (-4775 2625);
DISPLAY INVISIBLE (-4775 2625);
FORCEPROP 1 LASTPIN (-4825 2600) $PN 1
J 0
(-4815 2580);
DISPLAY 0.489362 (-4815 2580);
PAINT MONO (-4815 2580);
FORCEPROP 1 LASTPIN (-4825 2400) $PN 2
J 0
(-4815 2380);
DISPLAY 0.489362 (-4815 2380);
PAINT MONO (-4815 2380);
FORCEPROP 1 LAST MATERIAL X6S
J 0
(-4775 2400);
DISPLAY 0.489362 (-4775 2400);
PAINT SKYBLUE (-4775 2400);
FORCEPROP 1 LAST TOLERANCE 10%
J 0
(-4775 2450);
DISPLAY 0.489362 (-4775 2450);
PAINT SKYBLUE (-4775 2450);
FORCEPROP 1 LAST VALUE 1UF
J 0
(-4775 2550);
DISPLAY 0.489362 (-4775 2550);
PAINT SKYBLUE (-4775 2550);
FORCEPROP 1 LAST PART_NUMBER CH5104KEB02
J 0
(-4775 2350);
DISPLAY 0.489362 (-4775 2350);
PAINT SKYBLUE (-4775 2350);
FORCEPROP 1 LAST VOLTAGE 25V
J 0
(-4775 2500);
DISPLAY 0.489362 (-4775 2500);
PAINT SKYBLUE (-4775 2500);
FORCEPROP 1 LAST PACK_TYPE C0402
J 0
(-4775 2300);
DISPLAY 0.489362 (-4775 2300);
PAINT SKYBLUE (-4775 2300);
FORCEPROP 2 LAST CDS_LIB pure_quanta
J 0
(-4825 2500);
DISPLAY INVISIBLE (-4825 2500);
FORCEPROP 1 LAST PATH I88
J 0
(-4775 2650);
DISPLAY 0.978723 (-4775 2650);
PAINT WHITE (-4775 2650);
DISPLAY INVISIBLE (-4775 2650);
FORCEADD Q_RES..1
(-4500 1950);
FORCEPROP 1 LAST LOCATION PR198
J 0
(-4525 2000);
DISPLAY 0.489362 (-4525 2000);
PAINT SKYBLUE (-4525 2000);
FORCEPROP 0 LAST $SEC 1
J 0
(-4475 2025);
DISPLAY 0.680851 (-4475 2025);
PAINT MONO (-4475 2025);
DISPLAY INVISIBLE (-4475 2025);
FORCEPROP 0 LAST CDS_SEC 1
J 0
(-4475 2025);
DISPLAY 1.021277 (-4475 2025);
DISPLAY INVISIBLE (-4475 2025);
FORCEPROP 1 LASTPIN (-4600 1950) $PN 1
J 0
(-4588 1962);
DISPLAY 0.489362 (-4588 1962);
PAINT MONO (-4588 1962);
FORCEPROP 1 LASTPIN (-4400 1950) $PN 2
J 0
(-4438 1962);
DISPLAY 0.489362 (-4438 1962);
PAINT MONO (-4438 1962);
FORCEPROP 1 LAST PACK_TYPE 0402LF
J 0
(-4400 1850);
DISPLAY 0.489362 (-4400 1850);
PAINT SKYBLUE (-4400 1850);
FORCEPROP 1 LAST TOLERANCE 1%
J 0
(-4400 1975);
DISPLAY 0.489362 (-4400 1975);
PAINT SKYBLUE (-4400 1975);
FORCEPROP 1 LAST MATERIAL CHIP
J 0
(-4750 1850);
DISPLAY 0.489362 (-4750 1850);
PAINT SKYBLUE (-4750 1850);
FORCEPROP 1 LAST WATTAGE 1/16W
J 0
(-4400 1900);
DISPLAY 0.489362 (-4400 1900);
PAINT SKYBLUE (-4400 1900);
FORCEPROP 1 LAST VALUE 4.7
J 2
(-4600 1975);
DISPLAY 0.489362 (-4600 1975);
PAINT SKYBLUE (-4600 1975);
FORCEPROP 1 LAST PART_NUMBER CS-4702FB19
J 0
(-4750 1900);
DISPLAY 0.489362 (-4750 1900);
PAINT SKYBLUE (-4750 1900);
FORCEPROP 1 LAST PATH I89
J 0
(-4550 2100);
DISPLAY 0.978723 (-4550 2100);
PAINT WHITE (-4550 2100);
DISPLAY INVISIBLE (-4550 2100);
FORCEPROP 2 LAST CDS_LIB pure_quanta
J 0
(-4500 1950);
DISPLAY INVISIBLE (-4500 1950);
FORCEADD Q_RES..1
(-4125 500);
FORCEPROP 1 LAST LOCATION PR200
J 0
(-4150 550);
DISPLAY 0.489362 (-4150 550);
PAINT SKYBLUE (-4150 550);
FORCEPROP 0 LAST $SEC 1
J 0
(-4125 575);
DISPLAY 0.680851 (-4125 575);
PAINT MONO (-4125 575);
DISPLAY INVISIBLE (-4125 575);
FORCEPROP 0 LAST CDS_SEC 1
J 0
(-4125 575);
DISPLAY 1.021277 (-4125 575);
DISPLAY INVISIBLE (-4125 575);
FORCEPROP 1 LASTPIN (-4225 500) $PN 1
J 0
(-4213 512);
DISPLAY 0.489362 (-4213 512);
PAINT MONO (-4213 512);
FORCEPROP 1 LASTPIN (-4025 500) $PN 2
J 0
(-4063 512);
DISPLAY 0.489362 (-4063 512);
PAINT MONO (-4063 512);
FORCEPROP 1 LAST WATTAGE 1/16W
J 0
(-4025 450);
DISPLAY 0.489362 (-4025 450);
PAINT SKYBLUE (-4025 450);
FORCEPROP 1 LAST MATERIAL CHIP
J 0
(-4375 400);
DISPLAY 0.489362 (-4375 400);
PAINT SKYBLUE (-4375 400);
FORCEPROP 1 LAST TOLERANCE 5%
J 0
(-4000 525);
DISPLAY 0.489362 (-4000 525);
PAINT SKYBLUE (-4000 525);
FORCEPROP 1 LAST VALUE 0
J 2
(-4250 525);
DISPLAY 0.489362 (-4250 525);
PAINT SKYBLUE (-4250 525);
FORCEPROP 1 LAST PART_NUMBER CS00002JB38
J 0
(-4375 450);
DISPLAY 0.489362 (-4375 450);
PAINT SKYBLUE (-4375 450);
FORCEPROP 1 LAST PACK_TYPE 0402LF
J 0
(-4025 400);
DISPLAY 0.489362 (-4025 400);
PAINT SKYBLUE (-4025 400);
FORCEPROP 2 LAST CDS_LIB pure_quanta
J 0
(-4125 500);
DISPLAY INVISIBLE (-4125 500);
FORCEPROP 1 LAST PATH I90
J 0
(-4175 650);
DISPLAY 0.978723 (-4175 650);
PAINT WHITE (-4175 650);
DISPLAY INVISIBLE (-4175 650);
FORCEADD UNIVERSAL_GND..1
(-5325 850);
FORCEPROP 3 LASTPIN (-5325 900) SIG_NAME GND\g
J 0
(-5315 910);
DISPLAY 0.659574 (-5315 910);
PAINT MONO (-5315 910);
DISPLAY INVISIBLE (-5315 910);
FORCEPROP 2 LAST CDS_LIB pure_quanta_power
J 0
(-5325 850);
DISPLAY INVISIBLE (-5325 850);
FORCEPROP 1 LAST PATH I92
J 0
(-5250 850);
DISPLAY 0.872340 (-5250 850);
PAINT AQUA (-5250 850);
DISPLAY INVISIBLE (-5250 850);
FORCEPROP 1 LAST HDL_POWER GND
J 1
(-5300 775);
DISPLAY 0.872340 (-5300 775);
PAINT GREEN (-5300 775);
DISPLAY INVISIBLE (-5300 775);
FORCEADD Q_RES..1
(-7050 1300);
FORCEPROP 1 LAST LOCATION PR196
J 0
(-7100 1350);
DISPLAY 0.489362 (-7100 1350);
PAINT SKYBLUE (-7100 1350);
FORCEPROP 0 LAST $SEC 1
J 0
(-7050 1375);
DISPLAY 0.680851 (-7050 1375);
PAINT MONO (-7050 1375);
DISPLAY INVISIBLE (-7050 1375);
FORCEPROP 0 LAST CDS_SEC 1
J 0
(-7050 1375);
DISPLAY 1.021277 (-7050 1375);
DISPLAY INVISIBLE (-7050 1375);
FORCEPROP 1 LASTPIN (-7150 1300) $PN 1
J 0
(-7138 1312);
DISPLAY 0.489362 (-7138 1312);
PAINT MONO (-7138 1312);
FORCEPROP 1 LASTPIN (-6950 1300) $PN 2
J 0
(-6988 1312);
DISPLAY 0.489362 (-6988 1312);
PAINT MONO (-6988 1312);
FORCEPROP 1 LAST WATTAGE 1/16W
J 0
(-6950 1200);
DISPLAY 0.489362 (-6950 1200);
PAINT SKYBLUE (-6950 1200);
FORCEPROP 1 LAST MATERIAL EMPTY
J 0
(-7350 1200);
DISPLAY 0.489362 (-7350 1200);
PAINT RED (-7350 1200);
FORCEPROP 1 LAST TOLERANCE 1%
J 0
(-6925 1325);
DISPLAY 0.489362 (-6925 1325);
PAINT SKYBLUE (-6925 1325);
FORCEPROP 1 LAST VALUE 8.87K
J 2
(-7175 1325);
DISPLAY 0.489362 (-7175 1325);
PAINT SKYBLUE (-7175 1325);
FORCEPROP 1 LAST PART_NUMBER CS28872FB01
J 0
(-7350 1250);
DISPLAY 0.489362 (-7350 1250);
PAINT SKYBLUE (-7350 1250);
FORCEPROP 1 LAST PACK_TYPE 0402LF
J 0
(-6950 1250);
DISPLAY 0.489362 (-6950 1250);
PAINT SKYBLUE (-6950 1250);
FORCEPROP 2 LAST CDS_LIB pure_quanta
J 0
(-7050 1300);
DISPLAY INVISIBLE (-7050 1300);
FORCEPROP 1 LAST PATH I96
J 0
(-7100 1450);
DISPLAY 0.978723 (-7100 1450);
PAINT WHITE (-7100 1450);
DISPLAY INVISIBLE (-7100 1450);
FORCEADD OFFPAGE..2
R 2
(-7025 1600);
FORCEPROP 2 LAST $XR0 186 
J 0
(-7280 1600);
DISPLAY 0.638298 (-7280 1600);
PAINT MONO (-7280 1600);
FORCEPROP 2 LAST PATH I99
J 0
(-6975 1675);
DISPLAY 1.021277 (-6975 1675);
DISPLAY INVISIBLE (-6975 1675);
FORCEPROP 1 LAST COMMENT_BODY TRUE
J 2
(-6980 1505);
DISPLAY 0.872340 (-6980 1505);
PAINT GREEN (-6980 1505);
DISPLAY INVISIBLE (-6980 1505);
FORCEPROP 1 LAST OFFPAGE TRUE
J 2
(-7350 1475);
DISPLAY 0.872340 (-7350 1475);
PAINT GREEN (-7350 1475);
DISPLAY INVISIBLE (-7350 1475);
FORCEPROP 2 LAST CDS_LIB standard
J 2
(-7025 1600);
DISPLAY INVISIBLE (-7025 1600);
FORCEADD DNS..1
(-4475 900);
PAINT RED (-4475 900);
FORCEPROP 2 LAST CDS_LIB mstr_misc
J 0
(-4475 900);
DISPLAY INVISIBLE (-4475 900);
FORCEPROP 1 LAST COMMENT_BODY TRUE
R 1
J 0
(-4400 675);
DISPLAY 0.872340 (-4400 675);
PAINT GREEN (-4400 675);
DISPLAY INVISIBLE (-4400 675);
FORCEADD DNS..1
(-4475 1400);
PAINT RED (-4475 1400);
FORCEPROP 2 LAST CDS_LIB mstr_misc
J 0
(-4475 1400);
DISPLAY INVISIBLE (-4475 1400);
FORCEPROP 1 LAST COMMENT_BODY TRUE
R 1
J 0
(-4400 1175);
DISPLAY 0.872340 (-4400 1175);
PAINT GREEN (-4400 1175);
DISPLAY INVISIBLE (-4400 1175);
FORCEADD DNS..1
(-7050 1275);
PAINT RED (-7050 1275);
FORCEPROP 2 LAST CDS_LIB mstr_misc
J 0
(-7050 1275);
DISPLAY INVISIBLE (-7050 1275);
FORCEPROP 1 LAST COMMENT_BODY TRUE
R 1
J 0
(-6975 1050);
DISPLAY 0.872340 (-6975 1050);
PAINT GREEN (-6975 1050);
DISPLAY INVISIBLE (-6975 1050);
FORCEADD DNS..1
(-7150 4575);
PAINT RED (-7150 4575);
FORCEPROP 2 LAST CDS_LIB mstr_misc
J 0
(-7150 4575);
DISPLAY INVISIBLE (-7150 4575);
FORCEPROP 1 LAST COMMENT_BODY TRUE
R 1
J 0
(-7075 4350);
DISPLAY 0.872340 (-7075 4350);
PAINT GREEN (-7075 4350);
DISPLAY INVISIBLE (-7075 4350);
FORCEADD DNS..1
(-4475 4200);
PAINT RED (-4475 4200);
FORCEPROP 2 LAST CDS_LIB mstr_misc
J 0
(-4475 4200);
DISPLAY INVISIBLE (-4475 4200);
FORCEPROP 1 LAST COMMENT_BODY TRUE
R 1
J 0
(-4400 3975);
DISPLAY 0.872340 (-4400 3975);
PAINT GREEN (-4400 3975);
DISPLAY INVISIBLE (-4400 3975);
FORCEADD DNS..1
(-4475 4700);
PAINT RED (-4475 4700);
FORCEPROP 2 LAST CDS_LIB mstr_misc
J 0
(-4475 4700);
DISPLAY INVISIBLE (-4475 4700);
FORCEPROP 1 LAST COMMENT_BODY TRUE
R 1
J 0
(-4400 4475);
DISPLAY 0.872340 (-4400 4475);
PAINT GREEN (-4400 4475);
DISPLAY INVISIBLE (-4400 4475);
FORCEADD QUANTA_TITLE_BLOCK_C..1
(0 0);
FORCEPROP 0 LAST CDS_CON_LAST_MODIFIED Fri Mar 11 14:53:33 2022
J 0
(-1885 15);
DISPLAY INVISIBLE (-1885 15);
FORCEPROP 1 LAST CUSTOM_TXT_CDS <CON_LAST_MODIFIED>
J 0
(-1885 15);
DISPLAY 0.978723 (-1885 15);
FORCEPROP 2 LAST CUSTOM_TXT_CDS <XR_PAGE_TITLE>
J 0
(-7890 5250);
DISPLAY 0.638298 (-7890 5250);
PAINT PINK (-7890 5250);
DISPLAY INVISIBLE (-7890 5250);
FORCEPROP 1 LAST CUSTOM_TXT_CDS <NAME_2>
J 0
(-3175 50);
FORCEPROP 1 LAST CUSTOM_TXT_CDS <NAME_1>
J 0
(-3175 175);
FORCEPROP 1 LAST CUSTOM_TXT_CDS <Q_NUMBER>
J 0
(-1403 103);
DISPLAY 1.212766 (-1403 103);
FORCEPROP 1 LAST CUSTOM_TXT_CDS <Q_PROJ>
J 0
(-2382 102);
DISPLAY 1.212766 (-2382 102);
FORCEPROP 1 LAST CUSTOM_TXT_CDS <Q_REV>
J 0
(-184 103);
DISPLAY 1.212766 (-184 103);
FORCEPROP 1 LAST CUSTOM_TXT_CDS <CON_PAGE_NUM> OF <CON_TOTAL_PAGES>
J 0
(-446 18);
DISPLAY 0.978723 (-446 18);
FORCEPROP 1 LAST Q_DEPT BU9
J 1
(-3763 49);
DISPLAY 1.957447 (-3763 49);
PAINT GREEN (-3763 49);
FORCEPROP 1 LAST Q_TITLE PVDDCR_CPU0_P1 VR PHASE 3&4
J 0
(-9366 26);
DISPLAY 2.446809 (-9366 26);
PAINT GREEN (-9366 26);
FORCEPROP 1 LAST CDS_LMAN_SYM_OUTLINE -9475,6775,100,-125
J 0
(0 0);
DISPLAY 0.468085 (0 0);
PAINT GREEN (0 0);
DISPLAY INVISIBLE (0 0);
FORCEPROP 2 LAST CDS_LIB pure_quanta
J 0
(0 0);
DISPLAY INVISIBLE (0 0);
FORCEPROP 2 LAST PAGE_BORDER TRUE
J 0
(-7890 5250);
DISPLAY 0.638298 (-7890 5250);
PAINT PINK (-7890 5250);
DISPLAY INVISIBLE (-7890 5250);
FORCEPROP 1 LAST COMMENT_BODY TRUE
J 0
(12 -13);
DISPLAY 0.978723 (12 -13);
PAINT GREEN (12 -13);
DISPLAY INVISIBLE (12 -13);
FORCEPROP 2 LAST CDS_XR_PAGE_TITLE CR-188 : @T6G_MB_LIB.T6G(SCH_1):PAGE188
J 0
(-7890 5250);
DISPLAY 0.638298 (-7890 5250);
PAINT PINK (-7890 5250);
DISPLAY INVISIBLE (-7890 5250);
WIRE 16 -1 (-7775 4525)(-7775 4400);
WIRE 16 -1 (-7150 1300)(-7375 1300);
WIRE 16 -1 (-7375 1300)(-7375 1175);
WIRE 16 -1 (-7700 1225)(-7700 1100);
WIRE 16 -1 (-7450 5150)(-7450 5100);
WIRE 16 -1 (-7100 5725)(-7100 5600);
WIRE 16 -1 (-7350 1850)(-7350 1800);
WIRE 16 -1 (-7000 2425)(-7000 2300);
WIRE 16 -1 (-4450 4100)(-4450 4025);
WIRE 16 -1 (-4450 800)(-4450 725);
WIRE 16 -1 (-7250 4600)(-7475 4600);
WIRE 16 -1 (-7475 4600)(-7475 4475);
WIRE 16 -1 (-3525 1725)(-3525 1700);
WIRE 16 -1 (-3525 1700)(-5475 1700);
FORCEPROP 2 LAST SIG_NAME SW_PVDDCR_CPU0_P1_PH4
J 0
(-5360 1710);
DISPLAY 0.489362 (-5360 1710);
FORCEPROP 2 LASTPROP $XRERR UNIQUE?
J 0
(-5600 1710);
DISPLAY 0.638298 (-5600 1710);
PAINT MONO (-5600 1710);
DISPLAY INVISIBLE (-5600 1710);
WIRE 16 -1 (-3600 5025)(-3600 5000);
WIRE 16 -1 (-3600 5000)(-5550 5000);
FORCEPROP 2 LAST SIG_NAME SW_PVDDCR_CPU0_P1_PH3
J 0
(-5435 5010);
DISPLAY 0.489362 (-5435 5010);
FORCEPROP 2 LASTPROP $XRERR UNIQUE?
J 0
(-5675 5010);
DISPLAY 0.638298 (-5675 5010);
PAINT MONO (-5675 5010);
DISPLAY INVISIBLE (-5675 5010);
WIRE 16 -1 (-5550 4900)(-4450 4900);
FORCEPROP 2 LAST SIG_NAME SW_PVDDCR_CPU0_P1_SW3
J 0
(-5435 4910);
DISPLAY 0.489362 (-5435 4910);
FORCEPROP 2 LASTPROP $XRERR UNIQUE?
J 0
(-5675 4910);
DISPLAY 0.638298 (-5675 4910);
PAINT MONO (-5675 4910);
DISPLAY INVISIBLE (-5675 4910);
WIRE 16 -1 (-4450 4900)(-3050 4900);
WIRE 16 -1 (-4450 4800)(-4450 4900);
WIRE 16 -1 (-5550 5250)(-4675 5250);
FORCEPROP 2 LAST SIG_NAME SW_PVDDCR_CPU0_P1_BOOT3
J 0
(-5435 5260);
DISPLAY 0.489362 (-5435 5260);
FORCEPROP 2 LASTPROP $XRERR UNIQUE?
J 0
(-5675 5260);
DISPLAY 0.638298 (-5675 5260);
PAINT MONO (-5675 5260);
DISPLAY INVISIBLE (-5675 5260);
WIRE 16 -1 (-7875 1500)(-7700 1500);
WIRE 16 -1 (-6325 1500)(-7700 1500);
FORCEPROP 2 LAST SIG_NAME PVDDCR_CPU0_P1_VCCS
J 2
(-6385 1510);
DISPLAY 0.489362 (-6385 1510);
WIRE 16 -1 (-7700 1425)(-7700 1500);
WIRE 16 -1 (-6325 1000)(-6925 1000);
FORCEPROP 2 LAST SIG_NAME PVDDCR_CPU0_P1_PWM4
J 2
(-6385 1010);
DISPLAY 0.489362 (-6385 1010);
WIRE 16 -1 (-6325 1350)(-6775 1350);
FORCEPROP 2 LAST SIG_NAME NC_PVDDCR_CPU0_P1_DNC4
J 2
(-6385 1360);
DISPLAY 0.489362 (-6385 1360);
FORCEPROP 2 LASTPROP $XRERR UNIQUE?
J 0
(-7015 1350);
DISPLAY 0.638298 (-7015 1350);
PAINT MONO (-7015 1350);
DISPLAY INVISIBLE (-7015 1350);
WIRE 16 -1 (-6925 1750)(-6325 1750);
WIRE 16 -1 (-6925 1950)(-6925 1750);
WIRE 16 -1 (-6925 2125)(-6925 1950);
FORCEPROP 2 LAST SIG_NAME PVDDCR_CPU0_P1_VCC4
J 2
(-6410 1960);
DISPLAY 0.489362 (-6410 1960);
FORCEPROP 2 LASTPROP $XRERR UNIQUE?
J 0
(-6650 1960);
DISPLAY 0.638298 (-6650 1960);
PAINT MONO (-6650 1960);
DISPLAY INVISIBLE (-6650 1960);
WIRE 16 -1 (-6925 1950)(-6325 1950);
WIRE 16 -1 (-7350 2125)(-6925 2125);
WIRE 16 -1 (-7350 2400)(-7350 2125);
WIRE 16 -1 (-7350 2125)(-7350 2050);
WIRE 16 -1 (-6950 1300)(-6325 1300);
FORCEPROP 2 LAST SIG_NAME PVDDCR_CPU0_P1_LSET4
J 2
(-6385 1310);
DISPLAY 0.489362 (-6385 1310);
FORCEPROP 2 LASTPROP $XRERR UNIQUE?
J 0
(-6625 1310);
DISPLAY 0.638298 (-6625 1310);
PAINT MONO (-6625 1310);
DISPLAY INVISIBLE (-6625 1310);
WIRE 16 -1 (-6325 1100)(-6950 1100);
FORCEPROP 2 LAST SIG_NAME PVDDCR_CPU0_P1_TEMP0
J 2
(-6385 1110);
DISPLAY 0.489362 (-6385 1110);
WIRE 16 -1 (-6325 1600)(-6975 1600);
FORCEPROP 2 LAST SIG_NAME PVDDCR_CPU0_P1_IMON4
J 2
(-6385 1610);
DISPLAY 0.489362 (-6385 1610);
WIRE 16 -1 (-7350 2600)(-7350 2725);
WIRE 16 -1 (-7000 2725)(-7350 2725);
WIRE 16 -1 (-7350 2850)(-7350 2725);
WIRE 16 -1 (-6675 2725)(-7000 2725);
WIRE 16 -1 (-7000 2625)(-7000 2725);
WIRE 16 -1 (-6675 2250)(-6675 2725);
WIRE 16 -1 (-6675 2250)(-6325 2250);
WIRE 16 -1 (-5475 1000)(-5325 1000);
WIRE 16 -1 (-5325 1000)(-5325 1050);
WIRE 16 -1 (-5325 900)(-5325 1000);
WIRE 16 -1 (-5325 1050)(-5325 1100);
WIRE 16 -1 (-5475 1050)(-5325 1050);
WIRE 16 -1 (-5475 1100)(-5325 1100);
WIRE 16 -1 (-5325 1150)(-5325 1100);
WIRE 16 -1 (-5325 1150)(-5475 1150);
WIRE 16 -1 (-5475 1250)(-4950 1250);
FORCEPROP 2 LAST SIG_NAME NC_PVDDCR_CPU0_P1_GL2_4
J 0
(-5360 1260);
DISPLAY 0.489362 (-5360 1260);
FORCEPROP 2 LASTPROP $XRERR UNIQUE?
J 0
(-4920 1250);
DISPLAY 0.638298 (-4920 1250);
PAINT MONO (-4920 1250);
DISPLAY INVISIBLE (-4920 1250);
WIRE 16 -1 (-5475 1300)(-4950 1300);
FORCEPROP 2 LAST SIG_NAME NC_PVDDCR_CPU0_P1_GL1_4
J 0
(-5360 1310);
DISPLAY 0.489362 (-5360 1310);
FORCEPROP 2 LASTPROP $XRERR UNIQUE?
J 0
(-4920 1300);
DISPLAY 0.638298 (-4920 1300);
PAINT MONO (-4920 1300);
DISPLAY INVISIBLE (-4920 1300);
WIRE 16 -1 (-5475 1950)(-4600 1950);
FORCEPROP 2 LAST SIG_NAME SW_PVDDCR_CPU0_P1_BOOT4
J 0
(-5360 1960);
DISPLAY 0.489362 (-5360 1960);
FORCEPROP 2 LASTPROP $XRERR UNIQUE?
J 0
(-5600 1960);
DISPLAY 0.638298 (-5600 1960);
PAINT MONO (-5600 1960);
DISPLAY INVISIBLE (-5600 1960);
WIRE 16 -1 (-5475 1350)(-4725 1350);
WIRE 16 -1 (-4725 500)(-4725 1350);
WIRE 16 -1 (-4225 500)(-4725 500);
FORCEPROP 2 LAST SIG_NAME PVDDCR_CPU0_P1_VOS4
J 0
(-5360 1375);
DISPLAY 0.489362 (-5360 1375);
FORCEPROP 2 LASTPROP $XRERR UNIQUE?
J 0
(-5600 1375);
DISPLAY 0.638298 (-5600 1375);
PAINT MONO (-5600 1375);
DISPLAY INVISIBLE (-5600 1375);
WIRE 16 -1 (-4450 1300)(-4450 1000);
FORCEPROP 2 LAST SIG_NAME SW_PVDDCR_CPU0_P1_SW4_RC
J 0
(-4410 1110);
DISPLAY 0.489362 (-4410 1110);
FORCEPROP 2 LASTPROP $XRERR UNIQUE?
J 0
(-4650 1110);
DISPLAY 0.638298 (-4650 1110);
PAINT MONO (-4650 1110);
DISPLAY INVISIBLE (-4650 1110);
WIRE 16 -1 (-5375 2250)(-5375 2200);
WIRE 16 -1 (-5475 2250)(-5375 2250);
WIRE 16 -1 (-5375 2675)(-5375 2250);
WIRE 16 -1 (-5375 2200)(-5475 2200);
WIRE 16 -1 (-5375 2675)(-5200 2675);
WIRE 16 -1 (-5200 2675)(-4825 2675);
WIRE 16 -1 (-5200 2600)(-5200 2675);
WIRE 16 -1 (-4825 2675)(-4500 2675);
WIRE 16 -1 (-4825 2600)(-4825 2675);
WIRE 16 -1 (-4500 2675)(-4175 2675);
WIRE 16 -1 (-4500 2600)(-4500 2675);
WIRE 16 -1 (-4175 2675)(-3875 2675);
WIRE 16 -1 (-4175 2675)(-4175 2600);
WIRE 16 -1 (-3875 2750)(-3875 2675);
WIRE 16 -1 (-3875 2675)(-3875 2600);
WIRE 16 -1 (-5200 2400)(-5200 2275);
WIRE 16 -1 (-5200 2275)(-4825 2275);
WIRE 16 -1 (-4825 2275)(-4500 2275);
WIRE 16 -1 (-4825 2400)(-4825 2275);
WIRE 16 -1 (-4500 2275)(-4175 2275);
WIRE 16 -1 (-4500 2400)(-4500 2275);
WIRE 16 -1 (-3875 2275)(-4175 2275);
WIRE 16 -1 (-4175 2400)(-4175 2275);
WIRE 16 -1 (-3875 2400)(-3875 2275);
WIRE 16 -1 (-3875 2275)(-3875 2200);
WIRE 16 -1 (-4275 3800)(-4800 3800);
FORCEPROP 2 LAST SIG_NAME PVDDCR_CPU0_P1_VOS3
J 0
(-5435 4675);
DISPLAY 0.489362 (-5435 4675);
FORCEPROP 2 LASTPROP $XRERR UNIQUE?
J 0
(-5675 4675);
DISPLAY 0.638298 (-5675 4675);
PAINT MONO (-5675 4675);
DISPLAY INVISIBLE (-5675 4675);
WIRE 16 -1 (-4800 3800)(-4800 4650);
WIRE 16 -1 (-5550 4650)(-4800 4650);
WIRE 16 -1 (-7950 4800)(-7775 4800);
WIRE 16 -1 (-6400 4800)(-7775 4800);
FORCEPROP 2 LAST SIG_NAME PVDDCR_CPU0_P1_VCCS
J 2
(-6485 4810);
DISPLAY 0.489362 (-6485 4810);
WIRE 16 -1 (-7775 4725)(-7775 4800);
WIRE 16 -1 (-7450 5425)(-6950 5425);
WIRE 16 -1 (-7450 5700)(-7450 5425);
WIRE 16 -1 (-7450 5425)(-7450 5350);
WIRE 16 -1 (-6950 5425)(-6950 5250);
FORCEPROP 2 LAST SIG_NAME PVDDCR_CPU0_P1_VCC3
J 2
(-6485 5260);
DISPLAY 0.489362 (-6485 5260);
FORCEPROP 2 LASTPROP $XRERR UNIQUE?
J 0
(-6725 5260);
DISPLAY 0.638298 (-6725 5260);
PAINT MONO (-6725 5260);
DISPLAY INVISIBLE (-6725 5260);
WIRE 16 -1 (-6950 5250)(-6950 5050);
WIRE 16 -1 (-6950 5250)(-6400 5250);
WIRE 16 -1 (-6950 5050)(-6400 5050);
WIRE 16 -1 (-6400 4650)(-6850 4650);
FORCEPROP 2 LAST SIG_NAME NC_PVDDCR_CPU0_P1_DNC3
J 2
(-6485 4660);
DISPLAY 0.489362 (-6485 4660);
FORCEPROP 2 LASTPROP $XRERR UNIQUE?
J 0
(-7090 4650);
DISPLAY 0.638298 (-7090 4650);
PAINT MONO (-7090 4650);
DISPLAY INVISIBLE (-7090 4650);
WIRE 16 -1 (-7050 4600)(-6400 4600);
FORCEPROP 2 LAST SIG_NAME PVDDCR_CPU0_P1_LSET3
J 2
(-6485 4610);
DISPLAY 0.489362 (-6485 4610);
FORCEPROP 2 LASTPROP $XRERR UNIQUE?
J 0
(-6725 4610);
DISPLAY 0.638298 (-6725 4610);
PAINT MONO (-6725 4610);
DISPLAY INVISIBLE (-6725 4610);
WIRE 16 -1 (-6400 4900)(-7050 4900);
FORCEPROP 2 LAST SIG_NAME PVDDCR_CPU0_P1_IMON3
J 2
(-6485 4910);
DISPLAY 0.489362 (-6485 4910);
WIRE 16 -1 (-6400 4400)(-7025 4400);
FORCEPROP 2 LAST SIG_NAME PVDDCR_CPU0_P1_TEMP0
J 2
(-6485 4410);
DISPLAY 0.489362 (-6485 4410);
WIRE 16 -1 (-6400 4300)(-7000 4300);
FORCEPROP 2 LAST SIG_NAME PVDDCR_CPU0_P1_PWM3
J 2
(-6485 4310);
DISPLAY 0.489362 (-6485 4310);
WIRE 16 -1 (-7450 5900)(-7450 6025);
WIRE 16 -1 (-7450 6150)(-7450 6025);
WIRE 16 -1 (-7100 6025)(-7450 6025);
WIRE 16 -1 (-6750 6025)(-7100 6025);
WIRE 16 -1 (-7100 5925)(-7100 6025);
WIRE 16 -1 (-6750 5550)(-6750 6025);
WIRE 16 -1 (-6750 5550)(-6400 5550);
WIRE 16 -1 (-5550 4300)(-5400 4300);
WIRE 16 -1 (-5400 4300)(-5400 4350);
WIRE 16 -1 (-5400 4175)(-5400 4300);
WIRE 16 -1 (-5550 4350)(-5400 4350);
WIRE 16 -1 (-5400 4350)(-5400 4400);
WIRE 16 -1 (-5400 4450)(-5400 4400);
WIRE 16 -1 (-5550 4400)(-5400 4400);
WIRE 16 -1 (-5400 4450)(-5550 4450);
WIRE 16 -1 (-5550 5500)(-5450 5500);
WIRE 16 -1 (-5450 5550)(-5450 5500);
WIRE 16 -1 (-5450 5975)(-5450 5550);
WIRE 16 -1 (-5550 5550)(-5450 5550);
WIRE 16 -1 (-5450 5975)(-5325 5975);
WIRE 16 -1 (-5325 5975)(-4975 5975);
WIRE 16 -1 (-5325 5900)(-5325 5975);
WIRE 16 -1 (-4975 5975)(-4650 5975);
WIRE 16 -1 (-4975 5900)(-4975 5975);
WIRE 16 -1 (-4650 5975)(-4325 5975);
WIRE 16 -1 (-4650 5900)(-4650 5975);
WIRE 16 -1 (-4325 5975)(-4025 5975);
WIRE 16 -1 (-4325 5975)(-4325 5900);
WIRE 16 -1 (-4025 6050)(-4025 5975);
WIRE 16 -1 (-4025 5975)(-4025 5900);
WIRE 16 -1 (-5550 4600)(-5025 4600);
FORCEPROP 2 LAST SIG_NAME NC_PVDDCR_CPU0_P1_GL1_3
J 0
(-5435 4610);
DISPLAY 0.489362 (-5435 4610);
FORCEPROP 2 LASTPROP $XRERR UNIQUE?
J 0
(-4995 4600);
DISPLAY 0.638298 (-4995 4600);
PAINT MONO (-4995 4600);
DISPLAY INVISIBLE (-4995 4600);
WIRE 16 -1 (-5550 4550)(-5025 4550);
FORCEPROP 2 LAST SIG_NAME NC_PVDDCR_CPU0_P1_GL2_3
J 0
(-5435 4560);
DISPLAY 0.489362 (-5435 4560);
FORCEPROP 2 LASTPROP $XRERR UNIQUE?
J 0
(-4995 4550);
DISPLAY 0.638298 (-4995 4550);
PAINT MONO (-4995 4550);
DISPLAY INVISIBLE (-4995 4550);
WIRE 16 -1 (-5325 5700)(-5325 5575);
WIRE 16 -1 (-5325 5575)(-4975 5575);
WIRE 16 -1 (-4975 5700)(-4975 5575);
WIRE 16 -1 (-4975 5575)(-4650 5575);
WIRE 16 -1 (-4650 5575)(-4325 5575);
WIRE 16 -1 (-4650 5700)(-4650 5575);
WIRE 16 -1 (-4025 5575)(-4325 5575);
WIRE 16 -1 (-4325 5700)(-4325 5575);
WIRE 16 -1 (-4025 5700)(-4025 5575);
WIRE 16 -1 (-4025 5575)(-4025 5525);
WIRE 16 -1 (-4450 4600)(-4450 4300);
FORCEPROP 2 LAST SIG_NAME SW_PVDDCR_CPU0_P1_SW3_RC
J 0
(-4410 4410);
DISPLAY 0.489362 (-4410 4410);
FORCEPROP 2 LASTPROP $XRERR UNIQUE?
J 0
(-4650 4410);
DISPLAY 0.638298 (-4650 4410);
PAINT MONO (-4650 4410);
DISPLAY INVISIBLE (-4650 4410);
WIRE 16 -1 (-5475 1600)(-4450 1600);
FORCEPROP 2 LAST SIG_NAME SW_PVDDCR_CPU0_P1_SW4
J 0
(-5360 1610);
DISPLAY 0.489362 (-5360 1610);
FORCEPROP 2 LASTPROP $XRERR UNIQUE?
J 0
(-5600 1610);
DISPLAY 0.638298 (-5600 1610);
PAINT MONO (-5600 1610);
DISPLAY INVISIBLE (-5600 1610);
WIRE 16 -1 (-4450 1600)(-2950 1600);
WIRE 16 -1 (-4450 1500)(-4450 1600);
WIRE 16 -1 (-4400 1950)(-3525 1950);
FORCEPROP 2 LAST SIG_NAME SW_PVDDCR_CPU0_P1_BOOT4_RC
J 2
(-3560 1960);
DISPLAY 0.489362 (-3560 1960);
FORCEPROP 2 LASTPROP $XRERR UNIQUE?
J 0
(-3800 1960);
DISPLAY 0.638298 (-3800 1960);
PAINT MONO (-3800 1960);
DISPLAY INVISIBLE (-3800 1960);
WIRE 16 -1 (-3525 1950)(-3525 1925);
WIRE 16 -1 (-3400 1350)(-2950 1350);
FORCEPROP 2 LAST SIG_NAME IND_CPU0_P1_CPL3
J 0
(-3385 1360);
DISPLAY 0.489362 (-3385 1360);
WIRE 16 -1 (-1450 1600)(-1450 500);
WIRE 16 -1 (-2150 1600)(-1450 1600);
WIRE 16 -1 (-1450 1600)(-1200 1600);
WIRE 16 -1 (-1450 500)(-4025 500);
WIRE 16 -1 (-1200 1600)(-775 1600);
WIRE 16 -1 (-1200 1600)(-1200 1525);
WIRE 16 -1 (-775 1700)(-775 1600);
WIRE 16 -1 (-775 1600)(-775 1525);
WIRE 16 -1 (-1725 1275)(-1725 1350);
WIRE 16 -1 (-2150 1350)(-1725 1350);
WIRE 16 -1 (-1200 1325)(-1200 1200);
WIRE 16 -1 (-775 1200)(-1200 1200);
WIRE 16 -1 (-775 1325)(-775 1200);
WIRE 16 -1 (-775 1125)(-775 1200);
WIRE 16 -1 (-1375 4900)(-1375 3800);
WIRE 16 -1 (-1375 4900)(-1250 4900);
WIRE 16 -1 (-2250 4900)(-1375 4900);
WIRE 16 -1 (-1375 3800)(-4075 3800);
WIRE 16 -1 (-1250 4900)(-825 4900);
WIRE 16 -1 (-1250 4900)(-1250 4825);
WIRE 16 -1 (-825 5000)(-825 4900);
WIRE 16 -1 (-825 4900)(-825 4825);
WIRE 16 -1 (-4475 5250)(-3600 5250);
FORCEPROP 2 LAST SIG_NAME SW_PVDDCR_CPU0_P1_BOOT3_RC
J 2
(-3635 5260);
DISPLAY 0.489362 (-3635 5260);
FORCEPROP 2 LASTPROP $XRERR UNIQUE?
J 0
(-3875 5260);
DISPLAY 0.638298 (-3875 5260);
PAINT MONO (-3875 5260);
DISPLAY INVISIBLE (-3875 5260);
WIRE 16 -1 (-3600 5250)(-3600 5225);
WIRE 16 -1 (-3550 4650)(-3050 4650);
FORCEPROP 2 LAST SIG_NAME IND_CPU0_P1_CPL2
J 0
(-3535 4660);
DISPLAY 0.489362 (-3535 4660);
WIRE 16 -1 (-2250 4650)(-1725 4650);
FORCEPROP 2 LAST SIG_NAME IND_CPU0_P1_CPL3
J 0
(-2160 4660);
DISPLAY 0.489362 (-2160 4660);
WIRE 16 -1 (-1250 4625)(-1250 4500);
WIRE 16 -1 (-825 4500)(-1250 4500);
WIRE 16 -1 (-825 4625)(-825 4500);
WIRE 16 -1 (-825 4425)(-825 4500);
DOT 1 (-4450 4900);
DOT 1 (-4450 1600);
DOT 1 (-6925 1950);
DOT 1 (-1450 1600);
DOT 1 (-775 1600);
DOT 1 (-775 1200);
DOT 1 (-1200 1600);
DOT 1 (-6950 5250);
DOT 1 (-1375 4900);
DOT 1 (-1250 4900);
DOT 1 (-825 4500);
DOT 1 (-825 4900);
DOT 1 (-4025 5975);
DOT 1 (-4025 5575);
DOT 1 (-3875 2675);
DOT 1 (-3875 2275);
DOT 1 (-4325 5975);
DOT 1 (-4325 5575);
DOT 1 (-4650 5975);
DOT 1 (-5325 5975);
DOT 1 (-5450 5550);
DOT 1 (-5400 4400);
DOT 1 (-5400 4300);
DOT 1 (-5400 4350);
DOT 1 (-7100 6025);
DOT 1 (-7450 6025);
DOT 1 (-7450 5425);
DOT 1 (-7775 4800);
DOT 1 (-4175 2675);
DOT 1 (-4500 2675);
DOT 1 (-4175 2275);
DOT 1 (-4500 2275);
DOT 1 (-4825 2675);
DOT 1 (-4825 2275);
DOT 1 (-5200 2675);
DOT 1 (-5375 2250);
DOT 1 (-5325 1050);
DOT 1 (-5325 1100);
DOT 1 (-5325 1000);
DOT 1 (-7000 2725);
DOT 1 (-7350 2725);
DOT 1 (-7350 2125);
DOT 1 (-7700 1500);
DOT 1 (-4975 5575);
DOT 1 (-4975 5975);
DOT 1 (-4650 5575);
FORCENOTE
2ND=CV+15^0TZ01
(-2225 4975) 0;
DISPLAY LEFT (-2225 4975);
DISPLAY 0.638298 (-2225 4975);
PAINT WHITE (-2225 4975);
FORCENOTE
DCR=2-3,0.27M OHM
(-2225 5025) 0;
DISPLAY LEFT (-2225 5025);
DISPLAY 0.638298 (-2225 5025);
PAINT WHITE (-2225 5025);
FORCENOTE
PGL6303.151HLT
(-2225 5225) 0;
DISPLAY LEFT (-2225 5225);
DISPLAY 0.638298 (-2225 5225);
PAINT WHITE (-2225 5225);
FORCENOTE
ISAT:70A@100C
(-2225 5175) 0;
DISPLAY LEFT (-2225 5175);
DISPLAY 0.638298 (-2225 5175);
PAINT WHITE (-2225 5175);
FORCENOTE
DCR=1-4,0.105M OHM
(-2225 5075) 0;
DISPLAY LEFT (-2225 5075);
DISPLAY 0.638298 (-2225 5075);
PAINT WHITE (-2225 5075);
FORCENOTE
11.0*7.5*12.5
(-2225 5125) 0;
DISPLAY LEFT (-2225 5125);
DISPLAY 0.638298 (-2225 5125);
PAINT WHITE (-2225 5125);
FORCENOTE
PGL6303.151HLT
(-2150 1925) 0;
DISPLAY LEFT (-2150 1925);
DISPLAY 0.638298 (-2150 1925);
PAINT WHITE (-2150 1925);
FORCENOTE
ISAT:70A@100C
(-2150 1875) 0;
DISPLAY LEFT (-2150 1875);
DISPLAY 0.638298 (-2150 1875);
PAINT WHITE (-2150 1875);
FORCENOTE
DCR=1-4,0.105M OHM
(-2150 1775) 0;
DISPLAY LEFT (-2150 1775);
DISPLAY 0.638298 (-2150 1775);
PAINT WHITE (-2150 1775);
FORCENOTE
DCR=2-3,0.27M OHM
(-2150 1725) 0;
DISPLAY LEFT (-2150 1725);
DISPLAY 0.638298 (-2150 1725);
PAINT WHITE (-2150 1725);
FORCENOTE
2ND=CV+15^0TZ01
(-2150 1675) 0;
DISPLAY LEFT (-2150 1675);
DISPLAY 0.638298 (-2150 1675);
PAINT WHITE (-2150 1675);
FORCENOTE
11.0*7.5*12.5
(-2150 1825) 0;
DISPLAY LEFT (-2150 1825);
DISPLAY 0.638298 (-2150 1825);
PAINT WHITE (-2150 1825);
FORCENOTE
PVDDCR_CPU0_P1_PHASE3
(-6550 6300) 0;
DISPLAY LEFT (-6550 6300);
DISPLAY 1.595745 (-6550 6300);
PAINT WHITE (-6550 6300);
FORCENOTE
PVDDCR_CPU0_P1_PHASE4
(-6575 2925) 0;
DISPLAY LEFT (-6575 2925);
DISPLAY 1.595745 (-6575 2925);
PAINT WHITE (-6575 2925);
QUIT
